FILE_TYPE = MACRO_DRAWING;
SET COLOR_WIRE YELLOW;
SET COLOR_PROP ORANGE;
SET COLOR_DOT WHITE;
SET COLOR_ARC YELLOW;
SET COLOR_BODY GREEN;
SET COLOR_NOTE PURPLE;
SET PROP_DISPLAY VALUE;
SET PAGE_NUMBER P94;
FORCEADD OFFPAGE..2
R 2
(-3100 400);
FORCEPROP 2 LAST $XR0 94 
J 0
(-3324 400);
DISPLAY 0.638298 (-3324 400);
PAINT MONO (-3324 400);
FORCEPROP 2 LAST CDS_LIB standard
J 0
(-3100 400);
PAINT MONO (-3100 400);
DISPLAY INVISIBLE (-3100 400);
FORCEPROP 1 LAST OFFPAGE TRUE
J 2
(-3425 275);
DISPLAY 0.872340 (-3425 275);
DISPLAY INVISIBLE (-3425 275);
FORCEPROP 1 LAST COMMENT_BODY TRUE
J 2
(-3055 305);
DISPLAY 0.872340 (-3055 305);
PAINT GREEN (-3055 305);
DISPLAY INVISIBLE (-3055 305);
FORCEPROP 2 LAST PATH I1
J 0
(-3050 475);
DISPLAY 1.021277 (-3050 475);
DISPLAY INVISIBLE (-3050 475);
FORCEADD Q_RES..2
(-1950 200);
FORCEPROP 1 LAST PART_NUMBER CS35492FB03
J 0
(-1910 75);
DISPLAY 0.978723 (-1910 75);
DISPLAY INVISIBLE (-1910 75);
FORCEPROP 1 LAST VALUE 54.9K
J 0
(-1905 275);
DISPLAY 0.978723 (-1905 275);
FORCEPROP 1 LAST TOLERANCE 1%
J 0
(-1905 225);
DISPLAY 0.978723 (-1905 225);
FORCEPROP 1 LAST MATERIAL CHIP
J 0
(-1910 125);
DISPLAY 0.978723 (-1910 125);
FORCEPROP 1 LAST WATTAGE 1/16W
J 0
(-1910 175);
DISPLAY 0.978723 (-1910 175);
FORCEPROP 1 LAST PACK_TYPE 0402LF
J 0
(-1910 25);
DISPLAY 0.978723 (-1910 25);
FORCEPROP 1 LAST $LOCATION R38
J 0
(-1905 325);
DISPLAY 0.978723 (-1905 325);
FORCEPROP 1 LASTPIN (-1950 300) $PN 1
J 0
(-1945 262);
DISPLAY 0.787234 (-1945 262);
FORCEPROP 1 LASTPIN (-1950 100) $PN 2
J 0
(-1945 110);
DISPLAY 0.787234 (-1945 110);
FORCEPROP 2 LAST CDS_LIB pure_quanta
J 0
(-1950 200);
PAINT MONO (-1950 200);
DISPLAY INVISIBLE (-1950 200);
FORCEPROP 2 LAST CDS_LOCATION R38
J 0
(-1900 425);
DISPLAY 1.021277 (-1900 425);
DISPLAY INVISIBLE (-1900 425);
FORCEPROP 2 LAST $SEC 1
J 0
(-1900 425);
DISPLAY 0.680851 (-1900 425);
PAINT MONO (-1900 425);
DISPLAY INVISIBLE (-1900 425);
FORCEPROP 2 LAST CDS_SEC 1
J 0
(-1900 425);
DISPLAY 1.021277 (-1900 425);
DISPLAY INVISIBLE (-1900 425);
FORCEPROP 1 LAST PATH I10
J 0
(-1900 375);
DISPLAY 0.978723 (-1900 375);
PAINT WHITE (-1900 375);
DISPLAY INVISIBLE (-1900 375);
FORCEADD TAP..1
(-525 3800);
FORCEPROP 3 LASTPIN (-575 3800) SIG_NAME M_G_CPU0_SA_DQ<20>
J 0
(-565 3810);
DISPLAY 0.659574 (-565 3810);
PAINT MONO (-565 3810);
DISPLAY INVISIBLE (-565 3810);
FORCEPROP 1 LASTPIN (-575 3800) BN 20
J 0
(-587 3808);
DISPLAY 0.680851 (-587 3808);
PAINT GREEN (-587 3808);
FORCEPROP 2 LAST CDS_LIB standard
J 0
(-525 3800);
PAINT MONO (-525 3800);
DISPLAY INVISIBLE (-525 3800);
FORCEPROP 1 LAST BODY_TYPE PLUMBING
J 0
(-525 3850);
DISPLAY 0.872340 (-525 3850);
PAINT GREEN (-525 3850);
DISPLAY INVISIBLE (-525 3850);
FORCEPROP 1 LAST HDL_TAP TRUE
J 0
(-200 3675);
DISPLAY 0.872340 (-200 3675);
DISPLAY INVISIBLE (-200 3675);
FORCEPROP 1 LAST PATH I100
J 0
(-527 3800);
DISPLAY 0.872340 (-527 3800);
PAINT GREEN (-527 3800);
DISPLAY INVISIBLE (-527 3800);
FORCEADD TAP..1
(-525 3850);
FORCEPROP 3 LASTPIN (-575 3850) SIG_NAME M_G_CPU0_SA_DQ<21>
J 0
(-565 3860);
DISPLAY 0.659574 (-565 3860);
PAINT MONO (-565 3860);
DISPLAY INVISIBLE (-565 3860);
FORCEPROP 1 LASTPIN (-575 3850) BN 21
J 0
(-587 3858);
DISPLAY 0.680851 (-587 3858);
PAINT GREEN (-587 3858);
FORCEPROP 2 LAST CDS_LIB standard
J 0
(-525 3850);
PAINT MONO (-525 3850);
DISPLAY INVISIBLE (-525 3850);
FORCEPROP 1 LAST BODY_TYPE PLUMBING
J 0
(-525 3900);
DISPLAY 0.872340 (-525 3900);
PAINT GREEN (-525 3900);
DISPLAY INVISIBLE (-525 3900);
FORCEPROP 1 LAST HDL_TAP TRUE
J 0
(-200 3725);
DISPLAY 0.872340 (-200 3725);
DISPLAY INVISIBLE (-200 3725);
FORCEPROP 1 LAST PATH I101
J 0
(-527 3850);
DISPLAY 0.872340 (-527 3850);
PAINT GREEN (-527 3850);
DISPLAY INVISIBLE (-527 3850);
FORCEADD TAP..1
(-525 3900);
FORCEPROP 3 LASTPIN (-575 3900) SIG_NAME M_G_CPU0_SA_DQ<22>
J 0
(-565 3910);
DISPLAY 0.659574 (-565 3910);
PAINT MONO (-565 3910);
DISPLAY INVISIBLE (-565 3910);
FORCEPROP 1 LASTPIN (-575 3900) BN 22
J 0
(-587 3908);
DISPLAY 0.680851 (-587 3908);
PAINT GREEN (-587 3908);
FORCEPROP 2 LAST CDS_LIB standard
J 0
(-525 3900);
DISPLAY INVISIBLE (-525 3900);
FORCEPROP 1 LAST BODY_TYPE PLUMBING
J 0
(-525 3950);
DISPLAY 0.872340 (-525 3950);
PAINT GREEN (-525 3950);
DISPLAY INVISIBLE (-525 3950);
FORCEPROP 1 LAST HDL_TAP TRUE
J 0
(-200 3775);
DISPLAY 0.872340 (-200 3775);
DISPLAY INVISIBLE (-200 3775);
FORCEPROP 1 LAST PATH I102
J 0
(-527 3900);
DISPLAY 0.872340 (-527 3900);
PAINT GREEN (-527 3900);
DISPLAY INVISIBLE (-527 3900);
FORCEADD TAP..1
(-525 4000);
FORCEPROP 3 LASTPIN (-575 4000) SIG_NAME M_G_CPU0_SA_DQ<24>
J 0
(-565 4010);
DISPLAY 0.659574 (-565 4010);
PAINT MONO (-565 4010);
DISPLAY INVISIBLE (-565 4010);
FORCEPROP 1 LASTPIN (-575 4000) BN 24
J 0
(-587 4008);
DISPLAY 0.680851 (-587 4008);
PAINT GREEN (-587 4008);
FORCEPROP 2 LAST CDS_LIB standard
J 0
(-525 4000);
DISPLAY INVISIBLE (-525 4000);
FORCEPROP 1 LAST BODY_TYPE PLUMBING
J 0
(-525 4050);
DISPLAY 0.872340 (-525 4050);
PAINT GREEN (-525 4050);
DISPLAY INVISIBLE (-525 4050);
FORCEPROP 1 LAST HDL_TAP TRUE
J 0
(-200 3875);
DISPLAY 0.872340 (-200 3875);
DISPLAY INVISIBLE (-200 3875);
FORCEPROP 1 LAST PATH I103
J 0
(-527 4000);
DISPLAY 0.872340 (-527 4000);
PAINT GREEN (-527 4000);
DISPLAY INVISIBLE (-527 4000);
FORCEADD TAP..1
(-525 3950);
FORCEPROP 3 LASTPIN (-575 3950) SIG_NAME M_G_CPU0_SA_DQ<23>
J 0
(-565 3960);
DISPLAY 0.659574 (-565 3960);
PAINT MONO (-565 3960);
DISPLAY INVISIBLE (-565 3960);
FORCEPROP 1 LASTPIN (-575 3950) BN 23
J 0
(-587 3958);
DISPLAY 0.680851 (-587 3958);
PAINT GREEN (-587 3958);
FORCEPROP 2 LAST CDS_LIB standard
J 0
(-525 3950);
DISPLAY INVISIBLE (-525 3950);
FORCEPROP 1 LAST BODY_TYPE PLUMBING
J 0
(-525 4000);
DISPLAY 0.872340 (-525 4000);
PAINT GREEN (-525 4000);
DISPLAY INVISIBLE (-525 4000);
FORCEPROP 1 LAST HDL_TAP TRUE
J 0
(-200 3825);
DISPLAY 0.872340 (-200 3825);
DISPLAY INVISIBLE (-200 3825);
FORCEPROP 1 LAST PATH I104
J 0
(-527 3950);
DISPLAY 0.872340 (-527 3950);
PAINT GREEN (-527 3950);
DISPLAY INVISIBLE (-527 3950);
FORCEADD OFFPAGE..3
(300 2725);
FORCEPROP 2 LAST $XR1 95 
J 0
(604 2725);
DISPLAY 0.638298 (604 2725);
PAINT MONO (604 2725);
FORCEPROP 2 LAST $XR0 26 
J 0
(514 2725);
DISPLAY 0.638298 (514 2725);
PAINT MONO (514 2725);
FORCEPROP 2 LAST CDS_LIB standard
J 2
(300 2725);
DISPLAY INVISIBLE (300 2725);
FORCEPROP 1 LAST OFFPAGE TRUE
J 0
(625 2600);
DISPLAY 0.872340 (625 2600);
DISPLAY INVISIBLE (625 2600);
FORCEPROP 1 LAST COMMENT_BODY TRUE
J 0
(250 2625);
DISPLAY 0.872340 (250 2625);
PAINT GREEN (250 2625);
DISPLAY INVISIBLE (250 2625);
FORCEPROP 2 LAST PATH I105
J 0
(500 2800);
DISPLAY 1.021277 (500 2800);
DISPLAY INVISIBLE (500 2800);
FORCEADD OFFPAGE..1
(-3100 4375);
FORCEPROP 2 LAST $XR1 95 
J 0
(-3411 4375);
DISPLAY 0.638298 (-3411 4375);
PAINT MONO (-3411 4375);
FORCEPROP 2 LAST $XR0 26 
J 0
(-3321 4375);
DISPLAY 0.638298 (-3321 4375);
PAINT MONO (-3321 4375);
FORCEPROP 2 LAST CDS_LIB standard
J 0
(-3100 4375);
PAINT MONO (-3100 4375);
DISPLAY INVISIBLE (-3100 4375);
FORCEPROP 1 LAST OFFPAGE TRUE
J 0
(-2775 4250);
DISPLAY 0.872340 (-2775 4250);
DISPLAY INVISIBLE (-2775 4250);
FORCEPROP 1 LAST COMMENT_BODY TRUE
J 0
(-2975 4275);
DISPLAY 0.872340 (-2975 4275);
PAINT GREEN (-2975 4275);
DISPLAY INVISIBLE (-2975 4275);
FORCEPROP 2 LAST PATH I106
J 0
(-3050 4450);
DISPLAY 1.021277 (-3050 4450);
DISPLAY INVISIBLE (-3050 4450);
FORCEADD TAP..1
R 2
(-2175 4100);
FORCEPROP 3 LASTPIN (-2125 4100) SIG_NAME M_G_CPU0_SA_CA<1>
J 0
(-2115 4110);
DISPLAY 0.659574 (-2115 4110);
PAINT MONO (-2115 4110);
DISPLAY INVISIBLE (-2115 4110);
FORCEPROP 1 LASTPIN (-2125 4100) BN 1
J 2
(-2113 4108);
DISPLAY 0.680851 (-2113 4108);
PAINT GREEN (-2113 4108);
FORCEPROP 2 LAST CDS_LIB standard
J 0
(-2175 4100);
DISPLAY INVISIBLE (-2175 4100);
FORCEPROP 1 LAST BODY_TYPE PLUMBING
J 2
(-2175 4150);
DISPLAY 0.872340 (-2175 4150);
PAINT GREEN (-2175 4150);
DISPLAY INVISIBLE (-2175 4150);
FORCEPROP 1 LAST HDL_TAP TRUE
J 2
(-2500 3975);
DISPLAY 0.872340 (-2500 3975);
DISPLAY INVISIBLE (-2500 3975);
FORCEPROP 1 LAST PATH I107
J 2
(-2173 4100);
DISPLAY 0.872340 (-2173 4100);
PAINT GREEN (-2173 4100);
DISPLAY INVISIBLE (-2173 4100);
FORCEADD TAP..1
R 2
(-2175 4050);
FORCEPROP 3 LASTPIN (-2125 4050) SIG_NAME M_G_CPU0_SA_CA<0>
J 0
(-2115 4060);
DISPLAY 0.659574 (-2115 4060);
PAINT MONO (-2115 4060);
DISPLAY INVISIBLE (-2115 4060);
FORCEPROP 1 LASTPIN (-2125 4050) BN 0
J 2
(-2113 4058);
DISPLAY 0.680851 (-2113 4058);
PAINT GREEN (-2113 4058);
FORCEPROP 2 LAST CDS_LIB standard
J 0
(-2175 4050);
DISPLAY INVISIBLE (-2175 4050);
FORCEPROP 1 LAST BODY_TYPE PLUMBING
J 2
(-2175 4100);
DISPLAY 0.872340 (-2175 4100);
PAINT GREEN (-2175 4100);
DISPLAY INVISIBLE (-2175 4100);
FORCEPROP 1 LAST HDL_TAP TRUE
J 2
(-2500 3925);
DISPLAY 0.872340 (-2500 3925);
DISPLAY INVISIBLE (-2500 3925);
FORCEPROP 1 LAST PATH I108
J 2
(-2173 4050);
DISPLAY 0.872340 (-2173 4050);
PAINT GREEN (-2173 4050);
DISPLAY INVISIBLE (-2173 4050);
FORCEADD TAP..1
R 2
(-2175 4150);
FORCEPROP 3 LASTPIN (-2125 4150) SIG_NAME M_G_CPU0_SA_CA<2>
J 0
(-2115 4160);
DISPLAY 0.659574 (-2115 4160);
PAINT MONO (-2115 4160);
DISPLAY INVISIBLE (-2115 4160);
FORCEPROP 1 LASTPIN (-2125 4150) BN 2
J 2
(-2113 4158);
DISPLAY 0.680851 (-2113 4158);
PAINT GREEN (-2113 4158);
FORCEPROP 2 LAST CDS_LIB standard
J 0
(-2175 4150);
DISPLAY INVISIBLE (-2175 4150);
FORCEPROP 1 LAST BODY_TYPE PLUMBING
J 2
(-2175 4200);
DISPLAY 0.872340 (-2175 4200);
PAINT GREEN (-2175 4200);
DISPLAY INVISIBLE (-2175 4200);
FORCEPROP 1 LAST HDL_TAP TRUE
J 2
(-2500 4025);
DISPLAY 0.872340 (-2500 4025);
DISPLAY INVISIBLE (-2500 4025);
FORCEPROP 1 LAST PATH I109
J 2
(-2173 4150);
DISPLAY 0.872340 (-2173 4150);
PAINT GREEN (-2173 4150);
DISPLAY INVISIBLE (-2173 4150);
FORCEADD SCONN288_ADR50017P130CC..1
(-1350 2625);
FORCEPROP 1 LAST PART_NUMBER DFHST8FS461
J 0
(-1795 4647);
DISPLAY 0.723404 (-1795 4647);
PAINT GREEN (-1795 4647);
DISPLAY INVISIBLE (-1795 4647);
FORCEPROP 1 LAST MATERIAL IO
J 0
(-1795 4520);
DISPLAY 0.723404 (-1795 4520);
PAINT GREEN (-1795 4520);
FORCEPROP 2 LAST PART_TYPE SMLF
J 0
(-1800 4800);
DISPLAY 1.021277 (-1800 4800);
FORCEPROP 2 LAST VALUE SCONN288_ADR50017-P130CC
J 0
(-1800 4750);
DISPLAY 1.021277 (-1800 4750);
FORCEPROP 1 LAST $LOCATION J13
J 0
(-1800 4700);
DISPLAY 0.723404 (-1800 4700);
PAINT GREEN (-1800 4700);
FORCEPROP 0 LASTPIN (-1950 2000) $PN 62
J 2
(-1960 2010);
DISPLAY 0.680851 (-1960 2010);
PAINT MONO (-1960 2010);
FORCEPROP 0 LASTPIN (-1950 4050) $PN 66
J 2
(-1960 4060);
DISPLAY 0.680851 (-1960 4060);
PAINT MONO (-1960 4060);
FORCEPROP 0 LASTPIN (-1950 3650) $PN 76
J 2
(-1960 3660);
DISPLAY 0.680851 (-1960 3660);
PAINT MONO (-1960 3660);
FORCEPROP 0 LASTPIN (-1950 4100) $PN 211
J 2
(-1960 4110);
DISPLAY 0.680851 (-1960 4110);
PAINT MONO (-1960 4110);
FORCEPROP 0 LASTPIN (-1950 3700) $PN 221
J 2
(-1960 3710);
DISPLAY 0.680851 (-1960 3710);
PAINT MONO (-1960 3710);
FORCEPROP 0 LASTPIN (-1950 4150) $PN 68
J 2
(-1960 4160);
DISPLAY 0.680851 (-1960 4160);
PAINT MONO (-1960 4160);
FORCEPROP 0 LASTPIN (-1950 3750) $PN 78
J 2
(-1960 3760);
DISPLAY 0.680851 (-1960 3760);
PAINT MONO (-1960 3760);
FORCEPROP 0 LASTPIN (-1950 4200) $PN 213
J 2
(-1960 4210);
DISPLAY 0.680851 (-1960 4210);
PAINT MONO (-1960 4210);
FORCEPROP 0 LASTPIN (-1950 3800) $PN 223
J 2
(-1960 3810);
DISPLAY 0.680851 (-1960 3810);
PAINT MONO (-1960 3810);
FORCEPROP 0 LASTPIN (-1950 4250) $PN 70
J 2
(-1960 4260);
DISPLAY 0.680851 (-1960 4260);
PAINT MONO (-1960 4260);
FORCEPROP 0 LASTPIN (-1950 3850) $PN 80
J 2
(-1960 3860);
DISPLAY 0.680851 (-1960 3860);
PAINT MONO (-1960 3860);
FORCEPROP 0 LASTPIN (-1950 4300) $PN 215
J 2
(-1960 4310);
DISPLAY 0.680851 (-1960 4310);
PAINT MONO (-1960 4310);
FORCEPROP 0 LASTPIN (-1950 3900) $PN 225
J 2
(-1960 3910);
DISPLAY 0.680851 (-1960 3910);
PAINT MONO (-1960 3910);
FORCEPROP 0 LASTPIN (-1950 4350) $PN 72
J 2
(-1960 4360);
DISPLAY 0.680851 (-1960 4360);
PAINT MONO (-1960 4360);
FORCEPROP 0 LASTPIN (-1950 3950) $PN 82
J 2
(-1960 3960);
DISPLAY 0.680851 (-1960 3960);
PAINT MONO (-1960 3960);
FORCEPROP 0 LASTPIN (-1950 2600) $PN 51
J 2
(-1960 2610);
DISPLAY 0.680851 (-1960 2610);
PAINT MONO (-1960 2610);
FORCEPROP 0 LASTPIN (-1950 2150) $PN 96
J 2
(-1960 2160);
DISPLAY 0.680851 (-1960 2160);
PAINT MONO (-1960 2160);
FORCEPROP 0 LASTPIN (-1950 2650) $PN 53
J 2
(-1960 2660);
DISPLAY 0.680851 (-1960 2660);
PAINT MONO (-1960 2660);
FORCEPROP 0 LASTPIN (-1950 2200) $PN 98
J 2
(-1960 2210);
DISPLAY 0.680851 (-1960 2210);
PAINT MONO (-1960 2210);
FORCEPROP 0 LASTPIN (-1950 2700) $PN 196
J 2
(-1960 2710);
DISPLAY 0.680851 (-1960 2710);
PAINT MONO (-1960 2710);
FORCEPROP 0 LASTPIN (-1950 2250) $PN 241
J 2
(-1960 2260);
DISPLAY 0.680851 (-1960 2260);
PAINT MONO (-1960 2260);
FORCEPROP 0 LASTPIN (-1950 2750) $PN 198
J 2
(-1960 2760);
DISPLAY 0.680851 (-1960 2760);
PAINT MONO (-1960 2760);
FORCEPROP 0 LASTPIN (-1950 2300) $PN 243
J 2
(-1960 2310);
DISPLAY 0.680851 (-1960 2310);
PAINT MONO (-1960 2310);
FORCEPROP 0 LASTPIN (-1950 2800) $PN 58
J 2
(-1960 2810);
DISPLAY 0.680851 (-1960 2810);
PAINT MONO (-1960 2810);
FORCEPROP 0 LASTPIN (-1950 2350) $PN 89
J 2
(-1960 2360);
DISPLAY 0.680851 (-1960 2360);
PAINT MONO (-1960 2360);
FORCEPROP 0 LASTPIN (-1950 2850) $PN 60
J 2
(-1960 2860);
DISPLAY 0.680851 (-1960 2860);
PAINT MONO (-1960 2860);
FORCEPROP 0 LASTPIN (-1950 2400) $PN 91
J 2
(-1960 2410);
DISPLAY 0.680851 (-1960 2410);
PAINT MONO (-1960 2410);
FORCEPROP 0 LASTPIN (-1950 2900) $PN 203
J 2
(-1960 2910);
DISPLAY 0.680851 (-1960 2910);
PAINT MONO (-1960 2910);
FORCEPROP 0 LASTPIN (-1950 2450) $PN 234
J 2
(-1960 2460);
DISPLAY 0.680851 (-1960 2460);
PAINT MONO (-1960 2460);
FORCEPROP 0 LASTPIN (-1950 2950) $PN 205
J 2
(-1960 2960);
DISPLAY 0.680851 (-1960 2960);
PAINT MONO (-1960 2960);
FORCEPROP 0 LASTPIN (-1950 2500) $PN 236
J 2
(-1960 2510);
DISPLAY 0.680851 (-1960 2510);
PAINT MONO (-1960 2510);
FORCEPROP 0 LASTPIN (-1950 3050) $PN 218
J 2
(-1960 3060);
DISPLAY 0.680851 (-1960 3060);
PAINT MONO (-1960 3060);
FORCEPROP 0 LASTPIN (-1950 3100) $PN 217
J 2
(-1960 3110);
DISPLAY 0.680851 (-1960 3110);
PAINT MONO (-1960 3110);
FORCEPROP 0 LASTPIN (-1950 3350) $PN 64
J 2
(-1960 3360);
DISPLAY 0.680851 (-1960 3360);
PAINT MONO (-1960 3360);
FORCEPROP 0 LASTPIN (-1950 3200) $PN 84
J 2
(-1960 3210);
DISPLAY 0.680851 (-1960 3210);
PAINT MONO (-1960 3210);
FORCEPROP 0 LASTPIN (-1950 3400) $PN 209
J 2
(-1960 3410);
DISPLAY 0.680851 (-1960 3410);
PAINT MONO (-1960 3410);
FORCEPROP 0 LASTPIN (-1950 3250) $PN 229
J 2
(-1960 3260);
DISPLAY 0.680851 (-1960 3260);
PAINT MONO (-1960 3260);
FORCEPROP 0 LASTPIN (-750 2800) $PN 7
J 0
(-740 2810);
DISPLAY 0.680851 (-740 2810);
PAINT MONO (-740 2810);
FORCEPROP 0 LASTPIN (-750 1150) $PN 100
J 0
(-740 1160);
DISPLAY 0.680851 (-740 1160);
PAINT MONO (-740 1160);
FORCEPROP 0 LASTPIN (-750 2850) $PN 9
J 0
(-740 2860);
DISPLAY 0.680851 (-740 2860);
PAINT MONO (-740 2860);
FORCEPROP 0 LASTPIN (-750 1200) $PN 102
J 0
(-740 1210);
DISPLAY 0.680851 (-740 1210);
PAINT MONO (-740 1210);
FORCEPROP 0 LASTPIN (-750 2900) $PN 152
J 0
(-740 2910);
DISPLAY 0.680851 (-740 2910);
PAINT MONO (-740 2910);
FORCEPROP 0 LASTPIN (-750 1250) $PN 245
J 0
(-740 1260);
DISPLAY 0.680851 (-740 1260);
PAINT MONO (-740 1260);
FORCEPROP 0 LASTPIN (-750 2950) $PN 154
J 0
(-740 2960);
DISPLAY 0.680851 (-740 2960);
PAINT MONO (-740 2960);
FORCEPROP 0 LASTPIN (-750 1300) $PN 247
J 0
(-740 1310);
DISPLAY 0.680851 (-740 1310);
PAINT MONO (-740 1310);
FORCEPROP 0 LASTPIN (-750 3000) $PN 14
J 0
(-740 3010);
DISPLAY 0.680851 (-740 3010);
PAINT MONO (-740 3010);
FORCEPROP 0 LASTPIN (-750 1350) $PN 107
J 0
(-740 1360);
DISPLAY 0.680851 (-740 1360);
PAINT MONO (-740 1360);
FORCEPROP 0 LASTPIN (-750 3050) $PN 16
J 0
(-740 3060);
DISPLAY 0.680851 (-740 3060);
PAINT MONO (-740 3060);
FORCEPROP 0 LASTPIN (-750 1400) $PN 109
J 0
(-740 1410);
DISPLAY 0.680851 (-740 1410);
PAINT MONO (-740 1410);
FORCEPROP 0 LASTPIN (-750 3100) $PN 159
J 0
(-740 3110);
DISPLAY 0.680851 (-740 3110);
PAINT MONO (-740 3110);
FORCEPROP 0 LASTPIN (-750 1450) $PN 252
J 0
(-740 1460);
DISPLAY 0.680851 (-740 1460);
PAINT MONO (-740 1460);
FORCEPROP 0 LASTPIN (-750 3150) $PN 161
J 0
(-740 3160);
DISPLAY 0.680851 (-740 3160);
PAINT MONO (-740 3160);
FORCEPROP 0 LASTPIN (-750 1500) $PN 254
J 0
(-740 1510);
DISPLAY 0.680851 (-740 1510);
PAINT MONO (-740 1510);
FORCEPROP 0 LASTPIN (-750 3200) $PN 18
J 0
(-740 3210);
DISPLAY 0.680851 (-740 3210);
PAINT MONO (-740 3210);
FORCEPROP 0 LASTPIN (-750 1550) $PN 111
J 0
(-740 1560);
DISPLAY 0.680851 (-740 1560);
PAINT MONO (-740 1560);
FORCEPROP 0 LASTPIN (-750 3250) $PN 20
J 0
(-740 3260);
DISPLAY 0.680851 (-740 3260);
PAINT MONO (-740 3260);
FORCEPROP 0 LASTPIN (-750 1600) $PN 113
J 0
(-740 1610);
DISPLAY 0.680851 (-740 1610);
PAINT MONO (-740 1610);
FORCEPROP 0 LASTPIN (-750 3300) $PN 163
J 0
(-740 3310);
DISPLAY 0.680851 (-740 3310);
PAINT MONO (-740 3310);
FORCEPROP 0 LASTPIN (-750 1650) $PN 256
J 0
(-740 1660);
DISPLAY 0.680851 (-740 1660);
PAINT MONO (-740 1660);
FORCEPROP 0 LASTPIN (-750 3350) $PN 165
J 0
(-740 3360);
DISPLAY 0.680851 (-740 3360);
PAINT MONO (-740 3360);
FORCEPROP 0 LASTPIN (-750 1700) $PN 258
J 0
(-740 1710);
DISPLAY 0.680851 (-740 1710);
PAINT MONO (-740 1710);
FORCEPROP 0 LASTPIN (-750 3400) $PN 25
J 0
(-740 3410);
DISPLAY 0.680851 (-740 3410);
PAINT MONO (-740 3410);
FORCEPROP 0 LASTPIN (-750 1750) $PN 118
J 0
(-740 1760);
DISPLAY 0.680851 (-740 1760);
PAINT MONO (-740 1760);
FORCEPROP 0 LASTPIN (-750 3450) $PN 27
J 0
(-740 3460);
DISPLAY 0.680851 (-740 3460);
PAINT MONO (-740 3460);
FORCEPROP 0 LASTPIN (-750 1800) $PN 120
J 0
(-740 1810);
DISPLAY 0.680851 (-740 1810);
PAINT MONO (-740 1810);
FORCEPROP 0 LASTPIN (-750 3500) $PN 170
J 0
(-740 3510);
DISPLAY 0.680851 (-740 3510);
PAINT MONO (-740 3510);
FORCEPROP 0 LASTPIN (-750 1850) $PN 263
J 0
(-740 1860);
DISPLAY 0.680851 (-740 1860);
PAINT MONO (-740 1860);
FORCEPROP 0 LASTPIN (-750 3550) $PN 172
J 0
(-740 3560);
DISPLAY 0.680851 (-740 3560);
PAINT MONO (-740 3560);
FORCEPROP 0 LASTPIN (-750 1900) $PN 265
J 0
(-740 1910);
DISPLAY 0.680851 (-740 1910);
PAINT MONO (-740 1910);
FORCEPROP 0 LASTPIN (-750 3600) $PN 29
J 0
(-740 3610);
DISPLAY 0.680851 (-740 3610);
PAINT MONO (-740 3610);
FORCEPROP 0 LASTPIN (-750 1950) $PN 122
J 0
(-740 1960);
DISPLAY 0.680851 (-740 1960);
PAINT MONO (-740 1960);
FORCEPROP 0 LASTPIN (-750 3650) $PN 31
J 0
(-740 3660);
DISPLAY 0.680851 (-740 3660);
PAINT MONO (-740 3660);
FORCEPROP 0 LASTPIN (-750 2000) $PN 124
J 0
(-740 2010);
DISPLAY 0.680851 (-740 2010);
PAINT MONO (-740 2010);
FORCEPROP 0 LASTPIN (-750 3700) $PN 174
J 0
(-740 3710);
DISPLAY 0.680851 (-740 3710);
PAINT MONO (-740 3710);
FORCEPROP 0 LASTPIN (-750 2050) $PN 267
J 0
(-740 2060);
DISPLAY 0.680851 (-740 2060);
PAINT MONO (-740 2060);
FORCEPROP 0 LASTPIN (-750 3750) $PN 176
J 0
(-740 3760);
DISPLAY 0.680851 (-740 3760);
PAINT MONO (-740 3760);
FORCEPROP 0 LASTPIN (-750 2100) $PN 269
J 0
(-740 2110);
DISPLAY 0.680851 (-740 2110);
PAINT MONO (-740 2110);
FORCEPROP 0 LASTPIN (-750 3800) $PN 36
J 0
(-740 3810);
DISPLAY 0.680851 (-740 3810);
PAINT MONO (-740 3810);
FORCEPROP 0 LASTPIN (-750 2150) $PN 129
J 0
(-740 2160);
DISPLAY 0.680851 (-740 2160);
PAINT MONO (-740 2160);
FORCEPROP 0 LASTPIN (-750 3850) $PN 38
J 0
(-740 3860);
DISPLAY 0.680851 (-740 3860);
PAINT MONO (-740 3860);
FORCEPROP 0 LASTPIN (-750 2200) $PN 131
J 0
(-740 2210);
DISPLAY 0.680851 (-740 2210);
PAINT MONO (-740 2210);
FORCEPROP 0 LASTPIN (-750 3900) $PN 181
J 0
(-740 3910);
DISPLAY 0.680851 (-740 3910);
PAINT MONO (-740 3910);
FORCEPROP 0 LASTPIN (-750 2250) $PN 274
J 0
(-740 2260);
DISPLAY 0.680851 (-740 2260);
PAINT MONO (-740 2260);
FORCEPROP 0 LASTPIN (-750 3950) $PN 183
J 0
(-740 3960);
DISPLAY 0.680851 (-740 3960);
PAINT MONO (-740 3960);
FORCEPROP 0 LASTPIN (-750 2300) $PN 276
J 0
(-740 2310);
DISPLAY 0.680851 (-740 2310);
PAINT MONO (-740 2310);
FORCEPROP 0 LASTPIN (-750 4000) $PN 40
J 0
(-740 4010);
DISPLAY 0.680851 (-740 4010);
PAINT MONO (-740 4010);
FORCEPROP 0 LASTPIN (-750 2350) $PN 133
J 0
(-740 2360);
DISPLAY 0.680851 (-740 2360);
PAINT MONO (-740 2360);
FORCEPROP 0 LASTPIN (-750 4050) $PN 42
J 0
(-740 4060);
DISPLAY 0.680851 (-740 4060);
PAINT MONO (-740 4060);
FORCEPROP 0 LASTPIN (-750 2400) $PN 135
J 0
(-740 2410);
DISPLAY 0.680851 (-740 2410);
PAINT MONO (-740 2410);
FORCEPROP 0 LASTPIN (-750 4100) $PN 185
J 0
(-740 4110);
DISPLAY 0.680851 (-740 4110);
PAINT MONO (-740 4110);
FORCEPROP 0 LASTPIN (-750 2450) $PN 278
J 0
(-740 2460);
DISPLAY 0.680851 (-740 2460);
PAINT MONO (-740 2460);
FORCEPROP 0 LASTPIN (-750 4150) $PN 187
J 0
(-740 4160);
DISPLAY 0.680851 (-740 4160);
PAINT MONO (-740 4160);
FORCEPROP 0 LASTPIN (-750 2500) $PN 280
J 0
(-740 2510);
DISPLAY 0.680851 (-740 2510);
PAINT MONO (-740 2510);
FORCEPROP 0 LASTPIN (-750 4200) $PN 47
J 0
(-740 4210);
DISPLAY 0.680851 (-740 4210);
PAINT MONO (-740 4210);
FORCEPROP 0 LASTPIN (-750 2550) $PN 140
J 0
(-740 2560);
DISPLAY 0.680851 (-740 2560);
PAINT MONO (-740 2560);
FORCEPROP 0 LASTPIN (-750 4250) $PN 49
J 0
(-740 4260);
DISPLAY 0.680851 (-740 4260);
PAINT MONO (-740 4260);
FORCEPROP 0 LASTPIN (-750 2600) $PN 142
J 0
(-740 2610);
DISPLAY 0.680851 (-740 2610);
PAINT MONO (-740 2610);
FORCEPROP 0 LASTPIN (-750 4300) $PN 192
J 0
(-740 4310);
DISPLAY 0.680851 (-740 4310);
PAINT MONO (-740 4310);
FORCEPROP 0 LASTPIN (-750 2650) $PN 285
J 0
(-740 2660);
DISPLAY 0.680851 (-740 2660);
PAINT MONO (-740 2660);
FORCEPROP 0 LASTPIN (-750 4350) $PN 194
J 0
(-740 4360);
DISPLAY 0.680851 (-740 4360);
PAINT MONO (-740 4360);
FORCEPROP 0 LASTPIN (-750 2700) $PN 287
J 0
(-740 2710);
DISPLAY 0.680851 (-740 2710);
PAINT MONO (-740 2710);
FORCEPROP 0 LASTPIN (-1950 1850) $PN 148
J 2
(-1960 1860);
DISPLAY 0.680851 (-1960 1860);
PAINT MONO (-1960 1860);
FORCEPROP 0 LASTPIN (-1950 1750) $PN 4
J 2
(-1960 1760);
DISPLAY 0.680851 (-1960 1760);
PAINT MONO (-1960 1760);
FORCEPROP 0 LASTPIN (-1950 1800) $PN 5
J 2
(-1960 1810);
DISPLAY 0.680851 (-1960 1810);
PAINT MONO (-1960 1810);
FORCEPROP 0 LASTPIN (-1950 950) $PN 86
J 2
(-1960 960);
DISPLAY 0.680851 (-1960 960);
PAINT MONO (-1960 960);
FORCEPROP 0 LASTPIN (-1950 900) $PN 87
J 2
(-1960 910);
DISPLAY 0.680851 (-1960 910);
PAINT MONO (-1960 910);
FORCEPROP 0 LASTPIN (-1950 3550) $PN 74
J 2
(-1960 3560);
DISPLAY 0.680851 (-1960 3560);
PAINT MONO (-1960 3560);
FORCEPROP 0 LASTPIN (-1950 3500) $PN 227
J 2
(-1960 3510);
DISPLAY 0.680851 (-1960 3510);
PAINT MONO (-1960 3510);
FORCEPROP 0 LASTPIN (-1950 1500) $PN 147
J 2
(-1960 1510);
DISPLAY 0.680851 (-1960 1510);
PAINT MONO (-1960 1510);
FORCEPROP 0 LASTPIN (-1950 2050) $PN 207
J 2
(-1960 2060);
DISPLAY 0.680851 (-1960 2060);
PAINT MONO (-1960 2060);
FORCEPROP 0 LASTPIN (-1950 1100) $PN 2
J 2
(-1960 1110);
DISPLAY 0.680851 (-1960 1110);
PAINT MONO (-1960 1110);
FORCEPROP 0 LASTPIN (-1950 1150) $PN 144
J 2
(-1960 1160);
DISPLAY 0.680851 (-1960 1160);
PAINT MONO (-1960 1160);
FORCEPROP 0 LASTPIN (-1950 1200) $PN 149
J 2
(-1960 1210);
DISPLAY 0.680851 (-1960 1210);
PAINT MONO (-1960 1210);
FORCEPROP 0 LASTPIN (-1950 1250) $PN 150
J 2
(-1960 1260);
DISPLAY 0.680851 (-1960 1260);
PAINT MONO (-1960 1260);
FORCEPROP 0 LASTPIN (-1950 1300) $PN 220
J 2
(-1960 1310);
DISPLAY 0.680851 (-1960 1310);
PAINT MONO (-1960 1310);
FORCEPROP 0 LASTPIN (-1950 1350) $PN 231
J 2
(-1960 1360);
DISPLAY 0.680851 (-1960 1360);
PAINT MONO (-1960 1360);
FORCEPROP 0 LASTPIN (-1950 1400) $PN 232
J 2
(-1960 1410);
DISPLAY 0.680851 (-1960 1410);
PAINT MONO (-1960 1410);
FORCEPROP 0 LASTPIN (-1950 1900) $PN 3
J 2
(-1960 1910);
DISPLAY 0.680851 (-1960 1910);
PAINT MONO (-1960 1910);
FORCEPROP 1 LAST NEEDS_NO_SIZE TRUE
J 0
(-1350 2625);
DISPLAY 0.723404 (-1350 2625);
PAINT GREEN (-1350 2625);
DISPLAY INVISIBLE (-1350 2625);
FORCEPROP 1 LAST CDS_LMAN_SYM_OUTLINE -450,1875,450,-1875
J 0
(-1350 2625);
DISPLAY 0.468085 (-1350 2625);
PAINT GREEN (-1350 2625);
DISPLAY INVISIBLE (-1350 2625);
FORCEPROP 2 LAST CDS_LIB pure_quanta
J 0
(-1350 2625);
DISPLAY INVISIBLE (-1350 2625);
FORCEPROP 2 LAST CDS_LOCATION J13
J 0
(-1800 4850);
DISPLAY 1.021277 (-1800 4850);
DISPLAY INVISIBLE (-1800 4850);
FORCEPROP 0 LAST $SEC 1
J 0
(-1775 4850);
DISPLAY 0.680851 (-1775 4850);
PAINT MONO (-1775 4850);
DISPLAY INVISIBLE (-1775 4850);
FORCEPROP 2 LAST CDS_SEC 1
J 0
(-1800 4850);
DISPLAY 1.021277 (-1800 4850);
DISPLAY INVISIBLE (-1800 4850);
FORCEPROP 1 LAST PATH I11
J 0
(-1350 2625);
DISPLAY 0.723404 (-1350 2625);
PAINT GREEN (-1350 2625);
DISPLAY INVISIBLE (-1350 2625);
FORCEADD TAP..1
R 2
(-2175 4200);
FORCEPROP 3 LASTPIN (-2125 4200) SIG_NAME M_G_CPU0_SA_CA<3>
J 0
(-2115 4210);
DISPLAY 0.659574 (-2115 4210);
PAINT MONO (-2115 4210);
DISPLAY INVISIBLE (-2115 4210);
FORCEPROP 1 LASTPIN (-2125 4200) BN 3
J 2
(-2113 4208);
DISPLAY 0.680851 (-2113 4208);
PAINT GREEN (-2113 4208);
FORCEPROP 2 LAST CDS_LIB standard
J 0
(-2175 4200);
DISPLAY INVISIBLE (-2175 4200);
FORCEPROP 1 LAST BODY_TYPE PLUMBING
J 2
(-2175 4250);
DISPLAY 0.872340 (-2175 4250);
PAINT GREEN (-2175 4250);
DISPLAY INVISIBLE (-2175 4250);
FORCEPROP 1 LAST HDL_TAP TRUE
J 2
(-2500 4075);
DISPLAY 0.872340 (-2500 4075);
DISPLAY INVISIBLE (-2500 4075);
FORCEPROP 1 LAST PATH I110
J 2
(-2173 4200);
DISPLAY 0.872340 (-2173 4200);
PAINT GREEN (-2173 4200);
DISPLAY INVISIBLE (-2173 4200);
FORCEADD TAP..1
R 2
(-2175 4250);
FORCEPROP 3 LASTPIN (-2125 4250) SIG_NAME M_G_CPU0_SA_CA<4>
J 0
(-2115 4260);
DISPLAY 0.659574 (-2115 4260);
PAINT MONO (-2115 4260);
DISPLAY INVISIBLE (-2115 4260);
FORCEPROP 1 LASTPIN (-2125 4250) BN 4
J 2
(-2113 4258);
DISPLAY 0.680851 (-2113 4258);
PAINT GREEN (-2113 4258);
FORCEPROP 2 LAST CDS_LIB standard
J 0
(-2175 4250);
DISPLAY INVISIBLE (-2175 4250);
FORCEPROP 1 LAST BODY_TYPE PLUMBING
J 2
(-2175 4300);
DISPLAY 0.872340 (-2175 4300);
PAINT GREEN (-2175 4300);
DISPLAY INVISIBLE (-2175 4300);
FORCEPROP 1 LAST HDL_TAP TRUE
J 2
(-2500 4125);
DISPLAY 0.872340 (-2500 4125);
DISPLAY INVISIBLE (-2500 4125);
FORCEPROP 1 LAST PATH I111
J 2
(-2173 4250);
DISPLAY 0.872340 (-2173 4250);
PAINT GREEN (-2173 4250);
DISPLAY INVISIBLE (-2173 4250);
FORCEADD TAP..1
R 2
(-2175 4300);
FORCEPROP 3 LASTPIN (-2125 4300) SIG_NAME M_G_CPU0_SA_CA<5>
J 0
(-2115 4310);
DISPLAY 0.659574 (-2115 4310);
PAINT MONO (-2115 4310);
DISPLAY INVISIBLE (-2115 4310);
FORCEPROP 1 LASTPIN (-2125 4300) BN 5
J 2
(-2113 4308);
DISPLAY 0.680851 (-2113 4308);
PAINT GREEN (-2113 4308);
FORCEPROP 2 LAST CDS_LIB standard
J 0
(-2175 4300);
DISPLAY INVISIBLE (-2175 4300);
FORCEPROP 1 LAST BODY_TYPE PLUMBING
J 2
(-2175 4350);
DISPLAY 0.872340 (-2175 4350);
PAINT GREEN (-2175 4350);
DISPLAY INVISIBLE (-2175 4350);
FORCEPROP 1 LAST HDL_TAP TRUE
J 2
(-2500 4175);
DISPLAY 0.872340 (-2500 4175);
DISPLAY INVISIBLE (-2500 4175);
FORCEPROP 1 LAST PATH I112
J 2
(-2173 4300);
DISPLAY 0.872340 (-2173 4300);
PAINT GREEN (-2173 4300);
DISPLAY INVISIBLE (-2173 4300);
FORCEADD TAP..1
R 2
(-2175 4350);
FORCEPROP 3 LASTPIN (-2125 4350) SIG_NAME M_G_CPU0_SA_CA<6>
J 0
(-2115 4360);
DISPLAY 0.659574 (-2115 4360);
PAINT MONO (-2115 4360);
DISPLAY INVISIBLE (-2115 4360);
FORCEPROP 1 LASTPIN (-2125 4350) BN 6
J 2
(-2113 4358);
DISPLAY 0.680851 (-2113 4358);
PAINT GREEN (-2113 4358);
FORCEPROP 2 LAST CDS_LIB standard
J 0
(-2175 4350);
DISPLAY INVISIBLE (-2175 4350);
FORCEPROP 1 LAST BODY_TYPE PLUMBING
J 2
(-2175 4400);
DISPLAY 0.872340 (-2175 4400);
PAINT GREEN (-2175 4400);
DISPLAY INVISIBLE (-2175 4400);
FORCEPROP 1 LAST HDL_TAP TRUE
J 2
(-2500 4225);
DISPLAY 0.872340 (-2500 4225);
DISPLAY INVISIBLE (-2500 4225);
FORCEPROP 1 LAST PATH I113
J 2
(-2173 4350);
DISPLAY 0.872340 (-2173 4350);
PAINT GREEN (-2173 4350);
DISPLAY INVISIBLE (-2173 4350);
FORCEADD TAP..1
(-525 4050);
FORCEPROP 3 LASTPIN (-575 4050) SIG_NAME M_G_CPU0_SA_DQ<25>
J 0
(-565 4060);
DISPLAY 0.659574 (-565 4060);
PAINT MONO (-565 4060);
DISPLAY INVISIBLE (-565 4060);
FORCEPROP 1 LASTPIN (-575 4050) BN 25
J 0
(-587 4058);
DISPLAY 0.680851 (-587 4058);
PAINT GREEN (-587 4058);
FORCEPROP 2 LAST CDS_LIB standard
J 0
(-525 4050);
DISPLAY INVISIBLE (-525 4050);
FORCEPROP 1 LAST BODY_TYPE PLUMBING
J 0
(-525 4100);
DISPLAY 0.872340 (-525 4100);
PAINT GREEN (-525 4100);
DISPLAY INVISIBLE (-525 4100);
FORCEPROP 1 LAST HDL_TAP TRUE
J 0
(-200 3925);
DISPLAY 0.872340 (-200 3925);
DISPLAY INVISIBLE (-200 3925);
FORCEPROP 1 LAST PATH I114
J 0
(-527 4050);
DISPLAY 0.872340 (-527 4050);
PAINT GREEN (-527 4050);
DISPLAY INVISIBLE (-527 4050);
FORCEADD TAP..1
(-525 4100);
FORCEPROP 3 LASTPIN (-575 4100) SIG_NAME M_G_CPU0_SA_DQ<26>
J 0
(-565 4110);
DISPLAY 0.659574 (-565 4110);
PAINT MONO (-565 4110);
DISPLAY INVISIBLE (-565 4110);
FORCEPROP 1 LASTPIN (-575 4100) BN 26
J 0
(-587 4108);
DISPLAY 0.680851 (-587 4108);
PAINT GREEN (-587 4108);
FORCEPROP 2 LAST CDS_LIB standard
J 0
(-525 4100);
DISPLAY INVISIBLE (-525 4100);
FORCEPROP 1 LAST BODY_TYPE PLUMBING
J 0
(-525 4150);
DISPLAY 0.872340 (-525 4150);
PAINT GREEN (-525 4150);
DISPLAY INVISIBLE (-525 4150);
FORCEPROP 1 LAST HDL_TAP TRUE
J 0
(-200 3975);
DISPLAY 0.872340 (-200 3975);
DISPLAY INVISIBLE (-200 3975);
FORCEPROP 1 LAST PATH I115
J 0
(-527 4100);
DISPLAY 0.872340 (-527 4100);
PAINT GREEN (-527 4100);
DISPLAY INVISIBLE (-527 4100);
FORCEADD TAP..1
(-525 4150);
FORCEPROP 3 LASTPIN (-575 4150) SIG_NAME M_G_CPU0_SA_DQ<27>
J 0
(-565 4160);
DISPLAY 0.659574 (-565 4160);
PAINT MONO (-565 4160);
DISPLAY INVISIBLE (-565 4160);
FORCEPROP 1 LASTPIN (-575 4150) BN 27
J 0
(-587 4158);
DISPLAY 0.680851 (-587 4158);
PAINT GREEN (-587 4158);
FORCEPROP 2 LAST CDS_LIB standard
J 0
(-525 4150);
DISPLAY INVISIBLE (-525 4150);
FORCEPROP 1 LAST BODY_TYPE PLUMBING
J 0
(-525 4200);
DISPLAY 0.872340 (-525 4200);
PAINT GREEN (-525 4200);
DISPLAY INVISIBLE (-525 4200);
FORCEPROP 1 LAST HDL_TAP TRUE
J 0
(-200 4025);
DISPLAY 0.872340 (-200 4025);
DISPLAY INVISIBLE (-200 4025);
FORCEPROP 1 LAST PATH I116
J 0
(-527 4150);
DISPLAY 0.872340 (-527 4150);
PAINT GREEN (-527 4150);
DISPLAY INVISIBLE (-527 4150);
FORCEADD TAP..1
(-525 4200);
FORCEPROP 3 LASTPIN (-575 4200) SIG_NAME M_G_CPU0_SA_DQ<28>
J 0
(-565 4210);
DISPLAY 0.659574 (-565 4210);
PAINT MONO (-565 4210);
DISPLAY INVISIBLE (-565 4210);
FORCEPROP 1 LASTPIN (-575 4200) BN 28
J 0
(-587 4208);
DISPLAY 0.680851 (-587 4208);
PAINT GREEN (-587 4208);
FORCEPROP 2 LAST CDS_LIB standard
J 0
(-525 4200);
DISPLAY INVISIBLE (-525 4200);
FORCEPROP 1 LAST BODY_TYPE PLUMBING
J 0
(-525 4250);
DISPLAY 0.872340 (-525 4250);
PAINT GREEN (-525 4250);
DISPLAY INVISIBLE (-525 4250);
FORCEPROP 1 LAST HDL_TAP TRUE
J 0
(-200 4075);
DISPLAY 0.872340 (-200 4075);
DISPLAY INVISIBLE (-200 4075);
FORCEPROP 1 LAST PATH I117
J 0
(-527 4200);
DISPLAY 0.872340 (-527 4200);
PAINT GREEN (-527 4200);
DISPLAY INVISIBLE (-527 4200);
FORCEADD TAP..1
(-525 4300);
FORCEPROP 3 LASTPIN (-575 4300) SIG_NAME M_G_CPU0_SA_DQ<30>
J 0
(-565 4310);
DISPLAY 0.659574 (-565 4310);
PAINT MONO (-565 4310);
DISPLAY INVISIBLE (-565 4310);
FORCEPROP 1 LASTPIN (-575 4300) BN 30
J 0
(-587 4308);
DISPLAY 0.680851 (-587 4308);
PAINT GREEN (-587 4308);
FORCEPROP 2 LAST CDS_LIB standard
J 0
(-525 4300);
DISPLAY INVISIBLE (-525 4300);
FORCEPROP 1 LAST BODY_TYPE PLUMBING
J 0
(-525 4350);
DISPLAY 0.872340 (-525 4350);
PAINT GREEN (-525 4350);
DISPLAY INVISIBLE (-525 4350);
FORCEPROP 1 LAST HDL_TAP TRUE
J 0
(-200 4175);
DISPLAY 0.872340 (-200 4175);
DISPLAY INVISIBLE (-200 4175);
FORCEPROP 1 LAST PATH I118
J 0
(-527 4300);
DISPLAY 0.872340 (-527 4300);
PAINT GREEN (-527 4300);
DISPLAY INVISIBLE (-527 4300);
FORCEADD TAP..1
(-525 4250);
FORCEPROP 3 LASTPIN (-575 4250) SIG_NAME M_G_CPU0_SA_DQ<29>
J 0
(-565 4260);
DISPLAY 0.659574 (-565 4260);
PAINT MONO (-565 4260);
DISPLAY INVISIBLE (-565 4260);
FORCEPROP 1 LASTPIN (-575 4250) BN 29
J 0
(-587 4258);
DISPLAY 0.680851 (-587 4258);
PAINT GREEN (-587 4258);
FORCEPROP 2 LAST CDS_LIB standard
J 0
(-525 4250);
DISPLAY INVISIBLE (-525 4250);
FORCEPROP 1 LAST BODY_TYPE PLUMBING
J 0
(-525 4300);
DISPLAY 0.872340 (-525 4300);
PAINT GREEN (-525 4300);
DISPLAY INVISIBLE (-525 4300);
FORCEPROP 1 LAST HDL_TAP TRUE
J 0
(-200 4125);
DISPLAY 0.872340 (-200 4125);
DISPLAY INVISIBLE (-200 4125);
FORCEPROP 1 LAST PATH I119
J 0
(-527 4250);
DISPLAY 0.872340 (-527 4250);
PAINT GREEN (-527 4250);
DISPLAY INVISIBLE (-527 4250);
FORCEADD OFFPAGE..1
(-3100 2100);
FORCEPROP 2 LAST $XR3 97 
J 0
(-3352 2064);
DISPLAY 0.638298 (-3352 2064);
PAINT MONO (-3352 2064);
FORCEPROP 2 LAST $XR2 96 
J 0
(-3532 2100);
DISPLAY 0.638298 (-3532 2100);
PAINT MONO (-3532 2100);
FORCEPROP 2 LAST $XR1 95 
J 0
(-3442 2100);
DISPLAY 0.638298 (-3442 2100);
PAINT MONO (-3442 2100);
FORCEPROP 2 LAST $XR0 129 
J 0
(-3352 2100);
DISPLAY 0.638298 (-3352 2100);
PAINT MONO (-3352 2100);
FORCEPROP 2 LAST CDS_LIB standard
J 0
(-3100 2100);
PAINT MONO (-3100 2100);
DISPLAY INVISIBLE (-3100 2100);
FORCEPROP 1 LAST OFFPAGE TRUE
J 0
(-2775 1975);
DISPLAY 0.872340 (-2775 1975);
DISPLAY INVISIBLE (-2775 1975);
FORCEPROP 1 LAST COMMENT_BODY TRUE
J 0
(-2975 2000);
DISPLAY 0.872340 (-2975 2000);
PAINT GREEN (-2975 2000);
DISPLAY INVISIBLE (-2975 2000);
FORCEPROP 2 LAST PATH I12
J 0
(-3050 2175);
DISPLAY 1.021277 (-3050 2175);
DISPLAY INVISIBLE (-3050 2175);
FORCEADD TAP..1
(-525 4350);
FORCEPROP 3 LASTPIN (-575 4350) SIG_NAME M_G_CPU0_SA_DQ<31>
J 0
(-565 4360);
DISPLAY 0.659574 (-565 4360);
PAINT MONO (-565 4360);
DISPLAY INVISIBLE (-565 4360);
FORCEPROP 1 LASTPIN (-575 4350) BN 31
J 0
(-587 4358);
DISPLAY 0.680851 (-587 4358);
PAINT GREEN (-587 4358);
FORCEPROP 2 LAST CDS_LIB standard
J 0
(-525 4350);
DISPLAY INVISIBLE (-525 4350);
FORCEPROP 1 LAST BODY_TYPE PLUMBING
J 0
(-525 4400);
DISPLAY 0.872340 (-525 4400);
PAINT GREEN (-525 4400);
DISPLAY INVISIBLE (-525 4400);
FORCEPROP 1 LAST HDL_TAP TRUE
J 0
(-200 4225);
DISPLAY 0.872340 (-200 4225);
DISPLAY INVISIBLE (-200 4225);
FORCEPROP 1 LAST PATH I120
J 0
(-527 4350);
DISPLAY 0.872340 (-527 4350);
PAINT GREEN (-527 4350);
DISPLAY INVISIBLE (-527 4350);
FORCEADD OFFPAGE..3
(300 4375);
FORCEPROP 2 LAST $XR1 95 
J 0
(604 4375);
DISPLAY 0.638298 (604 4375);
PAINT MONO (604 4375);
FORCEPROP 2 LAST $XR0 26 
J 0
(514 4375);
DISPLAY 0.638298 (514 4375);
PAINT MONO (514 4375);
FORCEPROP 2 LAST CDS_LIB standard
J 2
(300 4375);
DISPLAY INVISIBLE (300 4375);
FORCEPROP 1 LAST OFFPAGE TRUE
J 0
(625 4250);
DISPLAY 0.872340 (625 4250);
DISPLAY INVISIBLE (625 4250);
FORCEPROP 1 LAST COMMENT_BODY TRUE
J 0
(250 4275);
DISPLAY 0.872340 (250 4275);
PAINT GREEN (250 4275);
DISPLAY INVISIBLE (250 4275);
FORCEPROP 2 LAST PATH I121
J 0
(500 4450);
DISPLAY 1.021277 (500 4450);
DISPLAY INVISIBLE (500 4450);
FORCEADD UNIVERSAL_GND..1
(1200 100);
FORCEPROP 3 LASTPIN (1200 150) SIG_NAME GND\g
J 0
(1210 160);
DISPLAY 0.659574 (1210 160);
PAINT MONO (1210 160);
DISPLAY INVISIBLE (1210 160);
FORCEPROP 2 LAST CDS_LIB logical_power
J 0
(1200 100);
PAINT MONO (1200 100);
DISPLAY INVISIBLE (1200 100);
FORCEPROP 1 LAST HDL_POWER GND
J 1
(1225 25);
DISPLAY 0.872340 (1225 25);
PAINT GREEN (1225 25);
DISPLAY INVISIBLE (1225 25);
FORCEPROP 1 LAST PATH I122
J 0
(1275 100);
DISPLAY 0.872340 (1275 100);
PAINT AQUA (1275 100);
DISPLAY INVISIBLE (1275 100);
FORCEADD Q_CAP..1
(1200 475);
FORCEPROP 1 LAST PART_NUMBER CH5221MEB00
J 0
(1250 325);
DISPLAY 0.978723 (1250 325);
DISPLAY INVISIBLE (1250 325);
FORCEPROP 1 LAST PACK_TYPE C0402
J 0
(1250 275);
DISPLAY 0.978723 (1250 275);
FORCEPROP 1 LAST TOLERANCE 20%
J 0
(1250 425);
DISPLAY 0.978723 (1250 425);
FORCEPROP 1 LAST MATERIAL X6S
J 0
(1250 375);
DISPLAY 0.978723 (1250 375);
FORCEPROP 1 LAST VOLTAGE 6.3V
J 0
(1250 475);
DISPLAY 0.978723 (1250 475);
FORCEPROP 1 LAST VALUE 2.2UF
J 0
(1250 525);
DISPLAY 0.978723 (1250 525);
FORCEPROP 1 LAST $LOCATION C38
J 0
(1250 575);
DISPLAY 0.978723 (1250 575);
FORCEPROP 1 LASTPIN (1200 575) $PN 1
J 0
(1210 555);
DISPLAY 0.787234 (1210 555);
FORCEPROP 1 LASTPIN (1200 375) $PN 2
J 0
(1210 355);
DISPLAY 0.787234 (1210 355);
FORCEPROP 2 LAST CDS_LIB pure_quanta
J 0
(1200 475);
PAINT MONO (1200 475);
DISPLAY INVISIBLE (1200 475);
FORCEPROP 2 LAST CDS_LOCATION C38
J 0
(1250 675);
DISPLAY 1.021277 (1250 675);
DISPLAY INVISIBLE (1250 675);
FORCEPROP 2 LAST $SEC 1
J 0
(1250 675);
DISPLAY 0.680851 (1250 675);
PAINT MONO (1250 675);
DISPLAY INVISIBLE (1250 675);
FORCEPROP 2 LAST CDS_SEC 1
J 0
(1250 675);
DISPLAY 1.021277 (1250 675);
DISPLAY INVISIBLE (1250 675);
FORCEPROP 1 LAST PATH I123
J 0
(1250 625);
DISPLAY 0.978723 (1250 625);
PAINT WHITE (1250 625);
DISPLAY INVISIBLE (1250 625);
FORCEADD VCC_CORE..1
(1200 800);
FORCEPROP 3 LASTPIN (1200 750) SIG_NAME P3V3_AUX\g
J 0
(1210 760);
DISPLAY 0.659574 (1210 760);
PAINT MONO (1210 760);
DISPLAY INVISIBLE (1210 760);
FORCEPROP 1 LAST HDL_POWER P3V3_AUX
J 1
(1200 850);
DISPLAY 1.148936 (1200 850);
PAINT GREEN (1200 850);
FORCEPROP 2 LAST CDS_LIB logical_power
J 0
(1200 800);
PAINT MONO (1200 800);
DISPLAY INVISIBLE (1200 800);
FORCEPROP 1 LAST PATH I124
J 0
(1250 825);
DISPLAY 0.872340 (1250 825);
PAINT AQUA (1250 825);
DISPLAY INVISIBLE (1250 825);
FORCEADD Q_CAP..1
(2200 475);
FORCEPROP 1 LAST PART_NUMBER CH6103KEA00
J 0
(2250 325);
DISPLAY 0.978723 (2250 325);
DISPLAY INVISIBLE (2250 325);
FORCEPROP 1 LAST TOLERANCE 10%
J 0
(2250 425);
DISPLAY 0.978723 (2250 425);
FORCEPROP 1 LAST PACK_TYPE C0805
J 0
(2250 275);
DISPLAY 0.978723 (2250 275);
FORCEPROP 1 LAST VOLTAGE 16V
J 0
(2250 475);
DISPLAY 0.978723 (2250 475);
FORCEPROP 1 LAST VALUE 10UF
J 0
(2250 525);
DISPLAY 0.978723 (2250 525);
FORCEPROP 1 LAST MATERIAL X6S
J 0
(2250 375);
DISPLAY 0.978723 (2250 375);
FORCEPROP 1 LAST $LOCATION C39
J 0
(2250 575);
DISPLAY 0.978723 (2250 575);
FORCEPROP 1 LASTPIN (2200 575) $PN 1
J 0
(2210 555);
DISPLAY 0.787234 (2210 555);
FORCEPROP 1 LASTPIN (2200 375) $PN 2
J 0
(2210 355);
DISPLAY 0.787234 (2210 355);
FORCEPROP 2 LAST CDS_LIB pure_quanta
J 0
(2200 475);
PAINT MONO (2200 475);
DISPLAY INVISIBLE (2200 475);
FORCEPROP 2 LAST CDS_LOCATION C39
J 0
(2250 675);
DISPLAY 1.021277 (2250 675);
DISPLAY INVISIBLE (2250 675);
FORCEPROP 2 LAST $SEC 1
J 0
(2250 675);
DISPLAY 0.680851 (2250 675);
PAINT MONO (2250 675);
DISPLAY INVISIBLE (2250 675);
FORCEPROP 2 LAST CDS_SEC 1
J 0
(2250 675);
DISPLAY 1.021277 (2250 675);
DISPLAY INVISIBLE (2250 675);
FORCEPROP 1 LAST PATH I125
J 0
(2250 625);
DISPLAY 0.978723 (2250 625);
PAINT WHITE (2250 625);
DISPLAY INVISIBLE (2250 625);
FORCEADD VCC_CORE..1
(2200 800);
FORCEPROP 3 LASTPIN (2200 750) SIG_NAME P12V_S3_AUX_CPU0_NVDIMM\g
J 0
(2210 760);
DISPLAY 0.659574 (2210 760);
PAINT MONO (2210 760);
DISPLAY INVISIBLE (2210 760);
FORCEPROP 1 LAST HDL_POWER P12V_S3_AUX_CPU0_NVDIMM
J 1
(2200 850);
DISPLAY 1.148936 (2200 850);
PAINT GREEN (2200 850);
FORCEPROP 2 LAST CDS_LIB logical_power
J 0
(2200 800);
PAINT MONO (2200 800);
DISPLAY INVISIBLE (2200 800);
FORCEPROP 1 LAST PATH I126
J 0
(2250 825);
DISPLAY 0.872340 (2250 825);
PAINT AQUA (2250 825);
DISPLAY INVISIBLE (2250 825);
FORCEADD TAP..1
(2225 2400);
FORCEPROP 3 LASTPIN (2175 2400) SIG_NAME M_G_CPU0_SB_DQS_DP<0>
J 0
(2185 2410);
DISPLAY 0.659574 (2185 2410);
PAINT MONO (2185 2410);
DISPLAY INVISIBLE (2185 2410);
FORCEPROP 1 LASTPIN (2175 2400) BN 0
J 0
(2163 2408);
DISPLAY 0.680851 (2163 2408);
PAINT GREEN (2163 2408);
FORCEPROP 2 LAST CDS_LIB standard
J 0
(2225 2400);
PAINT MONO (2225 2400);
DISPLAY INVISIBLE (2225 2400);
FORCEPROP 1 LAST BODY_TYPE PLUMBING
J 0
(2225 2450);
DISPLAY 0.872340 (2225 2450);
PAINT GREEN (2225 2450);
DISPLAY INVISIBLE (2225 2450);
FORCEPROP 1 LAST HDL_TAP TRUE
J 0
(2550 2275);
DISPLAY 0.872340 (2550 2275);
DISPLAY INVISIBLE (2550 2275);
FORCEPROP 1 LAST PATH I128
J 0
(2223 2400);
DISPLAY 0.872340 (2223 2400);
PAINT GREEN (2223 2400);
DISPLAY INVISIBLE (2223 2400);
FORCEADD TAP..1
(2225 2500);
FORCEPROP 3 LASTPIN (2175 2500) SIG_NAME M_G_CPU0_SB_DQS_DP<1>
J 0
(2185 2510);
DISPLAY 0.659574 (2185 2510);
PAINT MONO (2185 2510);
DISPLAY INVISIBLE (2185 2510);
FORCEPROP 1 LASTPIN (2175 2500) BN 1
J 0
(2163 2508);
DISPLAY 0.680851 (2163 2508);
PAINT GREEN (2163 2508);
FORCEPROP 2 LAST CDS_LIB standard
J 0
(2225 2500);
DISPLAY INVISIBLE (2225 2500);
FORCEPROP 1 LAST BODY_TYPE PLUMBING
J 0
(2225 2550);
DISPLAY 0.872340 (2225 2550);
PAINT GREEN (2225 2550);
DISPLAY INVISIBLE (2225 2550);
FORCEPROP 1 LAST HDL_TAP TRUE
J 0
(2550 2375);
DISPLAY 0.872340 (2550 2375);
DISPLAY INVISIBLE (2550 2375);
FORCEPROP 1 LAST PATH I129
J 0
(2223 2500);
DISPLAY 0.872340 (2223 2500);
PAINT GREEN (2223 2500);
DISPLAY INVISIBLE (2223 2500);
FORCEADD OFFPAGE..3
R 2
(-3100 2525);
FORCEPROP 2 LAST $XR1 95 
J 0
(-3439 2525);
DISPLAY 0.638298 (-3439 2525);
PAINT MONO (-3439 2525);
FORCEPROP 2 LAST $XR0 26 
J 0
(-3349 2525);
DISPLAY 0.638298 (-3349 2525);
PAINT MONO (-3349 2525);
FORCEPROP 2 LAST CDS_LIB standard
J 0
(-3100 2525);
PAINT MONO (-3100 2525);
DISPLAY INVISIBLE (-3100 2525);
FORCEPROP 1 LAST OFFPAGE TRUE
J 2
(-3425 2400);
DISPLAY 0.872340 (-3425 2400);
DISPLAY INVISIBLE (-3425 2400);
FORCEPROP 1 LAST COMMENT_BODY TRUE
J 2
(-3050 2425);
DISPLAY 0.872340 (-3050 2425);
PAINT GREEN (-3050 2425);
DISPLAY INVISIBLE (-3050 2425);
FORCEPROP 2 LAST PATH I13
J 0
(-3050 2600);
DISPLAY 1.021277 (-3050 2600);
DISPLAY INVISIBLE (-3050 2600);
FORCEADD TAP..1
(2400 2350);
FORCEPROP 3 LASTPIN (2350 2350) SIG_NAME M_G_CPU0_SB_DQS_DN<0>
J 0
(2360 2360);
DISPLAY 0.659574 (2360 2360);
PAINT MONO (2360 2360);
DISPLAY INVISIBLE (2360 2360);
FORCEPROP 1 LASTPIN (2350 2350) BN 0
J 0
(2338 2358);
DISPLAY 0.680851 (2338 2358);
PAINT GREEN (2338 2358);
FORCEPROP 2 LAST CDS_LIB standard
J 0
(2400 2350);
PAINT MONO (2400 2350);
DISPLAY INVISIBLE (2400 2350);
FORCEPROP 1 LAST BODY_TYPE PLUMBING
J 0
(2400 2400);
DISPLAY 0.872340 (2400 2400);
PAINT GREEN (2400 2400);
DISPLAY INVISIBLE (2400 2400);
FORCEPROP 1 LAST HDL_TAP TRUE
J 0
(2725 2225);
DISPLAY 0.872340 (2725 2225);
DISPLAY INVISIBLE (2725 2225);
FORCEPROP 1 LAST PATH I130
J 0
(2398 2350);
DISPLAY 0.872340 (2398 2350);
PAINT GREEN (2398 2350);
DISPLAY INVISIBLE (2398 2350);
FORCEADD TAP..1
(2400 2450);
FORCEPROP 3 LASTPIN (2350 2450) SIG_NAME M_G_CPU0_SB_DQS_DN<1>
J 0
(2360 2460);
DISPLAY 0.659574 (2360 2460);
PAINT MONO (2360 2460);
DISPLAY INVISIBLE (2360 2460);
FORCEPROP 1 LASTPIN (2350 2450) BN 1
J 0
(2338 2458);
DISPLAY 0.680851 (2338 2458);
PAINT GREEN (2338 2458);
FORCEPROP 2 LAST CDS_LIB standard
J 0
(2400 2450);
DISPLAY INVISIBLE (2400 2450);
FORCEPROP 1 LAST BODY_TYPE PLUMBING
J 0
(2400 2500);
DISPLAY 0.872340 (2400 2500);
PAINT GREEN (2400 2500);
DISPLAY INVISIBLE (2400 2500);
FORCEPROP 1 LAST HDL_TAP TRUE
J 0
(2725 2325);
DISPLAY 0.872340 (2725 2325);
DISPLAY INVISIBLE (2725 2325);
FORCEPROP 1 LAST PATH I131
J 0
(2398 2450);
DISPLAY 0.872340 (2398 2450);
PAINT GREEN (2398 2450);
DISPLAY INVISIBLE (2398 2450);
FORCEADD TAP..1
(2225 2600);
FORCEPROP 3 LASTPIN (2175 2600) SIG_NAME M_G_CPU0_SB_DQS_DP<2>
J 0
(2185 2610);
DISPLAY 0.659574 (2185 2610);
PAINT MONO (2185 2610);
DISPLAY INVISIBLE (2185 2610);
FORCEPROP 1 LASTPIN (2175 2600) BN 2
J 0
(2163 2608);
DISPLAY 0.680851 (2163 2608);
PAINT GREEN (2163 2608);
FORCEPROP 2 LAST CDS_LIB standard
J 0
(2225 2600);
DISPLAY INVISIBLE (2225 2600);
FORCEPROP 1 LAST BODY_TYPE PLUMBING
J 0
(2225 2650);
DISPLAY 0.872340 (2225 2650);
PAINT GREEN (2225 2650);
DISPLAY INVISIBLE (2225 2650);
FORCEPROP 1 LAST HDL_TAP TRUE
J 0
(2550 2475);
DISPLAY 0.872340 (2550 2475);
DISPLAY INVISIBLE (2550 2475);
FORCEPROP 1 LAST PATH I132
J 0
(2223 2600);
DISPLAY 0.872340 (2223 2600);
PAINT GREEN (2223 2600);
DISPLAY INVISIBLE (2223 2600);
FORCEADD TAP..1
(2225 2700);
FORCEPROP 3 LASTPIN (2175 2700) SIG_NAME M_G_CPU0_SB_DQS_DP<3>
J 0
(2185 2710);
DISPLAY 0.659574 (2185 2710);
PAINT MONO (2185 2710);
DISPLAY INVISIBLE (2185 2710);
FORCEPROP 1 LASTPIN (2175 2700) BN 3
J 0
(2163 2708);
DISPLAY 0.680851 (2163 2708);
PAINT GREEN (2163 2708);
FORCEPROP 2 LAST CDS_LIB standard
J 0
(2225 2700);
PAINT MONO (2225 2700);
DISPLAY INVISIBLE (2225 2700);
FORCEPROP 1 LAST BODY_TYPE PLUMBING
J 0
(2225 2750);
DISPLAY 0.872340 (2225 2750);
PAINT GREEN (2225 2750);
DISPLAY INVISIBLE (2225 2750);
FORCEPROP 1 LAST HDL_TAP TRUE
J 0
(2550 2575);
DISPLAY 0.872340 (2550 2575);
DISPLAY INVISIBLE (2550 2575);
FORCEPROP 1 LAST PATH I133
J 0
(2223 2700);
DISPLAY 0.872340 (2223 2700);
PAINT GREEN (2223 2700);
DISPLAY INVISIBLE (2223 2700);
FORCEADD TAP..1
(2400 2550);
FORCEPROP 3 LASTPIN (2350 2550) SIG_NAME M_G_CPU0_SB_DQS_DN<2>
J 0
(2360 2560);
DISPLAY 0.659574 (2360 2560);
PAINT MONO (2360 2560);
DISPLAY INVISIBLE (2360 2560);
FORCEPROP 1 LASTPIN (2350 2550) BN 2
J 0
(2338 2558);
DISPLAY 0.680851 (2338 2558);
PAINT GREEN (2338 2558);
FORCEPROP 2 LAST CDS_LIB standard
J 0
(2400 2550);
DISPLAY INVISIBLE (2400 2550);
FORCEPROP 1 LAST BODY_TYPE PLUMBING
J 0
(2400 2600);
DISPLAY 0.872340 (2400 2600);
PAINT GREEN (2400 2600);
DISPLAY INVISIBLE (2400 2600);
FORCEPROP 1 LAST HDL_TAP TRUE
J 0
(2725 2425);
DISPLAY 0.872340 (2725 2425);
DISPLAY INVISIBLE (2725 2425);
FORCEPROP 1 LAST PATH I134
J 0
(2398 2550);
DISPLAY 0.872340 (2398 2550);
PAINT GREEN (2398 2550);
DISPLAY INVISIBLE (2398 2550);
FORCEADD TAP..1
(2400 2750);
FORCEPROP 3 LASTPIN (2350 2750) SIG_NAME M_G_CPU0_SB_DQS_DN<4>
J 0
(2360 2760);
DISPLAY 0.659574 (2360 2760);
PAINT MONO (2360 2760);
DISPLAY INVISIBLE (2360 2760);
FORCEPROP 1 LASTPIN (2350 2750) BN 4
J 0
(2338 2758);
DISPLAY 0.680851 (2338 2758);
PAINT GREEN (2338 2758);
FORCEPROP 2 LAST CDS_LIB standard
J 0
(2400 2750);
PAINT MONO (2400 2750);
DISPLAY INVISIBLE (2400 2750);
FORCEPROP 1 LAST BODY_TYPE PLUMBING
J 0
(2400 2800);
DISPLAY 0.872340 (2400 2800);
PAINT GREEN (2400 2800);
DISPLAY INVISIBLE (2400 2800);
FORCEPROP 1 LAST HDL_TAP TRUE
J 0
(2725 2625);
DISPLAY 0.872340 (2725 2625);
DISPLAY INVISIBLE (2725 2625);
FORCEPROP 1 LAST PATH I135
J 0
(2398 2750);
DISPLAY 0.872340 (2398 2750);
PAINT GREEN (2398 2750);
DISPLAY INVISIBLE (2398 2750);
FORCEADD TAP..1
(2400 2650);
FORCEPROP 3 LASTPIN (2350 2650) SIG_NAME M_G_CPU0_SB_DQS_DN<3>
J 0
(2360 2660);
DISPLAY 0.659574 (2360 2660);
PAINT MONO (2360 2660);
DISPLAY INVISIBLE (2360 2660);
FORCEPROP 1 LASTPIN (2350 2650) BN 3
J 0
(2338 2658);
DISPLAY 0.680851 (2338 2658);
PAINT GREEN (2338 2658);
FORCEPROP 2 LAST CDS_LIB standard
J 0
(2400 2650);
PAINT MONO (2400 2650);
DISPLAY INVISIBLE (2400 2650);
FORCEPROP 1 LAST BODY_TYPE PLUMBING
J 0
(2400 2700);
DISPLAY 0.872340 (2400 2700);
PAINT GREEN (2400 2700);
DISPLAY INVISIBLE (2400 2700);
FORCEPROP 1 LAST HDL_TAP TRUE
J 0
(2725 2525);
DISPLAY 0.872340 (2725 2525);
DISPLAY INVISIBLE (2725 2525);
FORCEPROP 1 LAST PATH I136
J 0
(2398 2650);
DISPLAY 0.872340 (2398 2650);
PAINT GREEN (2398 2650);
DISPLAY INVISIBLE (2398 2650);
FORCEADD TAP..1
(2225 2800);
FORCEPROP 3 LASTPIN (2175 2800) SIG_NAME M_G_CPU0_SB_DQS_DP<4>
J 0
(2185 2810);
DISPLAY 0.659574 (2185 2810);
PAINT MONO (2185 2810);
DISPLAY INVISIBLE (2185 2810);
FORCEPROP 1 LASTPIN (2175 2800) BN 4
J 0
(2163 2808);
DISPLAY 0.680851 (2163 2808);
PAINT GREEN (2163 2808);
FORCEPROP 2 LAST CDS_LIB standard
J 0
(2225 2800);
PAINT MONO (2225 2800);
DISPLAY INVISIBLE (2225 2800);
FORCEPROP 1 LAST BODY_TYPE PLUMBING
J 0
(2225 2850);
DISPLAY 0.872340 (2225 2850);
PAINT GREEN (2225 2850);
DISPLAY INVISIBLE (2225 2850);
FORCEPROP 1 LAST HDL_TAP TRUE
J 0
(2550 2675);
DISPLAY 0.872340 (2550 2675);
DISPLAY INVISIBLE (2550 2675);
FORCEPROP 1 LAST PATH I137
J 0
(2223 2800);
DISPLAY 0.872340 (2223 2800);
PAINT GREEN (2223 2800);
DISPLAY INVISIBLE (2223 2800);
FORCEADD TAP..1
(2225 3000);
FORCEPROP 3 LASTPIN (2175 3000) SIG_NAME M_G_CPU0_SB_DQS_DP<6>
J 0
(2185 3010);
DISPLAY 0.659574 (2185 3010);
PAINT MONO (2185 3010);
DISPLAY INVISIBLE (2185 3010);
FORCEPROP 1 LASTPIN (2175 3000) BN 6
J 0
(2163 3008);
DISPLAY 0.680851 (2163 3008);
PAINT GREEN (2163 3008);
FORCEPROP 2 LAST CDS_LIB standard
J 0
(2225 3000);
DISPLAY INVISIBLE (2225 3000);
FORCEPROP 1 LAST BODY_TYPE PLUMBING
J 0
(2225 3050);
DISPLAY 0.872340 (2225 3050);
PAINT GREEN (2225 3050);
DISPLAY INVISIBLE (2225 3050);
FORCEPROP 1 LAST HDL_TAP TRUE
J 0
(2550 2875);
DISPLAY 0.872340 (2550 2875);
DISPLAY INVISIBLE (2550 2875);
FORCEPROP 1 LAST PATH I138
J 0
(2223 3000);
DISPLAY 0.872340 (2223 3000);
PAINT GREEN (2223 3000);
DISPLAY INVISIBLE (2223 3000);
FORCEADD TAP..1
(2225 2900);
FORCEPROP 3 LASTPIN (2175 2900) SIG_NAME M_G_CPU0_SB_DQS_DP<5>
J 0
(2185 2910);
DISPLAY 0.659574 (2185 2910);
PAINT MONO (2185 2910);
DISPLAY INVISIBLE (2185 2910);
FORCEPROP 1 LASTPIN (2175 2900) BN 5
J 0
(2163 2908);
DISPLAY 0.680851 (2163 2908);
PAINT GREEN (2163 2908);
FORCEPROP 2 LAST CDS_LIB standard
J 0
(2225 2900);
DISPLAY INVISIBLE (2225 2900);
FORCEPROP 1 LAST BODY_TYPE PLUMBING
J 0
(2225 2950);
DISPLAY 0.872340 (2225 2950);
PAINT GREEN (2225 2950);
DISPLAY INVISIBLE (2225 2950);
FORCEPROP 1 LAST HDL_TAP TRUE
J 0
(2550 2775);
DISPLAY 0.872340 (2550 2775);
DISPLAY INVISIBLE (2550 2775);
FORCEPROP 1 LAST PATH I139
J 0
(2223 2900);
DISPLAY 0.872340 (2223 2900);
PAINT GREEN (2223 2900);
DISPLAY INVISIBLE (2223 2900);
FORCEADD OFFPAGE..3
R 2
(-3100 2975);
FORCEPROP 2 LAST $XR1 95 
J 0
(-3439 2975);
DISPLAY 0.638298 (-3439 2975);
PAINT MONO (-3439 2975);
FORCEPROP 2 LAST $XR0 26 
J 0
(-3349 2975);
DISPLAY 0.638298 (-3349 2975);
PAINT MONO (-3349 2975);
FORCEPROP 2 LAST CDS_LIB standard
J 0
(-3100 2975);
PAINT MONO (-3100 2975);
DISPLAY INVISIBLE (-3100 2975);
FORCEPROP 1 LAST OFFPAGE TRUE
J 2
(-3425 2850);
DISPLAY 0.872340 (-3425 2850);
DISPLAY INVISIBLE (-3425 2850);
FORCEPROP 1 LAST COMMENT_BODY TRUE
J 2
(-3050 2875);
DISPLAY 0.872340 (-3050 2875);
PAINT GREEN (-3050 2875);
DISPLAY INVISIBLE (-3050 2875);
FORCEPROP 2 LAST PATH I14
J 0
(-3050 3050);
DISPLAY 1.021277 (-3050 3050);
DISPLAY INVISIBLE (-3050 3050);
FORCEADD TAP..1
(2400 2850);
FORCEPROP 3 LASTPIN (2350 2850) SIG_NAME M_G_CPU0_SB_DQS_DN<5>
J 0
(2360 2860);
DISPLAY 0.659574 (2360 2860);
PAINT MONO (2360 2860);
DISPLAY INVISIBLE (2360 2860);
FORCEPROP 1 LASTPIN (2350 2850) BN 5
J 0
(2338 2858);
DISPLAY 0.680851 (2338 2858);
PAINT GREEN (2338 2858);
FORCEPROP 2 LAST CDS_LIB standard
J 0
(2400 2850);
DISPLAY INVISIBLE (2400 2850);
FORCEPROP 1 LAST BODY_TYPE PLUMBING
J 0
(2400 2900);
DISPLAY 0.872340 (2400 2900);
PAINT GREEN (2400 2900);
DISPLAY INVISIBLE (2400 2900);
FORCEPROP 1 LAST HDL_TAP TRUE
J 0
(2725 2725);
DISPLAY 0.872340 (2725 2725);
DISPLAY INVISIBLE (2725 2725);
FORCEPROP 1 LAST PATH I140
J 0
(2398 2850);
DISPLAY 0.872340 (2398 2850);
PAINT GREEN (2398 2850);
DISPLAY INVISIBLE (2398 2850);
FORCEADD TAP..1
(2400 2950);
FORCEPROP 3 LASTPIN (2350 2950) SIG_NAME M_G_CPU0_SB_DQS_DN<6>
J 0
(2360 2960);
DISPLAY 0.659574 (2360 2960);
PAINT MONO (2360 2960);
DISPLAY INVISIBLE (2360 2960);
FORCEPROP 1 LASTPIN (2350 2950) BN 6
J 0
(2338 2958);
DISPLAY 0.680851 (2338 2958);
PAINT GREEN (2338 2958);
FORCEPROP 2 LAST CDS_LIB standard
J 0
(2400 2950);
DISPLAY INVISIBLE (2400 2950);
FORCEPROP 1 LAST BODY_TYPE PLUMBING
J 0
(2400 3000);
DISPLAY 0.872340 (2400 3000);
PAINT GREEN (2400 3000);
DISPLAY INVISIBLE (2400 3000);
FORCEPROP 1 LAST HDL_TAP TRUE
J 0
(2725 2825);
DISPLAY 0.872340 (2725 2825);
DISPLAY INVISIBLE (2725 2825);
FORCEPROP 1 LAST PATH I141
J 0
(2398 2950);
DISPLAY 0.872340 (2398 2950);
PAINT GREEN (2398 2950);
DISPLAY INVISIBLE (2398 2950);
FORCEADD TAP..1
(2225 3100);
FORCEPROP 3 LASTPIN (2175 3100) SIG_NAME M_G_CPU0_SB_DQS_DP<7>
J 0
(2185 3110);
DISPLAY 0.659574 (2185 3110);
PAINT MONO (2185 3110);
DISPLAY INVISIBLE (2185 3110);
FORCEPROP 1 LASTPIN (2175 3100) BN 7
J 0
(2163 3108);
DISPLAY 0.680851 (2163 3108);
PAINT GREEN (2163 3108);
FORCEPROP 2 LAST CDS_LIB standard
J 0
(2225 3100);
DISPLAY INVISIBLE (2225 3100);
FORCEPROP 1 LAST BODY_TYPE PLUMBING
J 0
(2225 3150);
DISPLAY 0.872340 (2225 3150);
PAINT GREEN (2225 3150);
DISPLAY INVISIBLE (2225 3150);
FORCEPROP 1 LAST HDL_TAP TRUE
J 0
(2550 2975);
DISPLAY 0.872340 (2550 2975);
DISPLAY INVISIBLE (2550 2975);
FORCEPROP 1 LAST PATH I142
J 0
(2223 3100);
DISPLAY 0.872340 (2223 3100);
PAINT GREEN (2223 3100);
DISPLAY INVISIBLE (2223 3100);
FORCEADD TAP..1
(2225 3200);
FORCEPROP 3 LASTPIN (2175 3200) SIG_NAME M_G_CPU0_SB_DQS_DP<8>
J 0
(2185 3210);
DISPLAY 0.659574 (2185 3210);
PAINT MONO (2185 3210);
DISPLAY INVISIBLE (2185 3210);
FORCEPROP 1 LASTPIN (2175 3200) BN 8
J 0
(2163 3208);
DISPLAY 0.680851 (2163 3208);
PAINT GREEN (2163 3208);
FORCEPROP 2 LAST CDS_LIB standard
J 0
(2225 3200);
DISPLAY INVISIBLE (2225 3200);
FORCEPROP 1 LAST BODY_TYPE PLUMBING
J 0
(2225 3250);
DISPLAY 0.872340 (2225 3250);
PAINT GREEN (2225 3250);
DISPLAY INVISIBLE (2225 3250);
FORCEPROP 1 LAST HDL_TAP TRUE
J 0
(2550 3075);
DISPLAY 0.872340 (2550 3075);
DISPLAY INVISIBLE (2550 3075);
FORCEPROP 1 LAST PATH I143
J 0
(2223 3200);
DISPLAY 0.872340 (2223 3200);
PAINT GREEN (2223 3200);
DISPLAY INVISIBLE (2223 3200);
FORCEADD TAP..1
(2400 3050);
FORCEPROP 3 LASTPIN (2350 3050) SIG_NAME M_G_CPU0_SB_DQS_DN<7>
J 0
(2360 3060);
DISPLAY 0.659574 (2360 3060);
PAINT MONO (2360 3060);
DISPLAY INVISIBLE (2360 3060);
FORCEPROP 1 LASTPIN (2350 3050) BN 7
J 0
(2338 3058);
DISPLAY 0.680851 (2338 3058);
PAINT GREEN (2338 3058);
FORCEPROP 2 LAST CDS_LIB standard
J 0
(2400 3050);
DISPLAY INVISIBLE (2400 3050);
FORCEPROP 1 LAST BODY_TYPE PLUMBING
J 0
(2400 3100);
DISPLAY 0.872340 (2400 3100);
PAINT GREEN (2400 3100);
DISPLAY INVISIBLE (2400 3100);
FORCEPROP 1 LAST HDL_TAP TRUE
J 0
(2725 2925);
DISPLAY 0.872340 (2725 2925);
DISPLAY INVISIBLE (2725 2925);
FORCEPROP 1 LAST PATH I144
J 0
(2398 3050);
DISPLAY 0.872340 (2398 3050);
PAINT GREEN (2398 3050);
DISPLAY INVISIBLE (2398 3050);
FORCEADD TAP..1
(2400 3150);
FORCEPROP 3 LASTPIN (2350 3150) SIG_NAME M_G_CPU0_SB_DQS_DN<8>
J 0
(2360 3160);
DISPLAY 0.659574 (2360 3160);
PAINT MONO (2360 3160);
DISPLAY INVISIBLE (2360 3160);
FORCEPROP 1 LASTPIN (2350 3150) BN 8
J 0
(2338 3158);
DISPLAY 0.680851 (2338 3158);
PAINT GREEN (2338 3158);
FORCEPROP 2 LAST CDS_LIB standard
J 0
(2400 3150);
DISPLAY INVISIBLE (2400 3150);
FORCEPROP 1 LAST BODY_TYPE PLUMBING
J 0
(2400 3200);
DISPLAY 0.872340 (2400 3200);
PAINT GREEN (2400 3200);
DISPLAY INVISIBLE (2400 3200);
FORCEPROP 1 LAST HDL_TAP TRUE
J 0
(2725 3025);
DISPLAY 0.872340 (2725 3025);
DISPLAY INVISIBLE (2725 3025);
FORCEPROP 1 LAST PATH I145
J 0
(2398 3150);
DISPLAY 0.872340 (2398 3150);
PAINT GREEN (2398 3150);
DISPLAY INVISIBLE (2398 3150);
FORCEADD TAP..1
(2400 3250);
FORCEPROP 3 LASTPIN (2350 3250) SIG_NAME M_G_CPU0_SB_DQS_DN<9>
J 0
(2360 3260);
DISPLAY 0.659574 (2360 3260);
PAINT MONO (2360 3260);
DISPLAY INVISIBLE (2360 3260);
FORCEPROP 1 LASTPIN (2350 3250) BN 9
J 0
(2338 3258);
DISPLAY 0.680851 (2338 3258);
PAINT GREEN (2338 3258);
FORCEPROP 2 LAST CDS_LIB standard
J 0
(2400 3250);
DISPLAY INVISIBLE (2400 3250);
FORCEPROP 1 LAST BODY_TYPE PLUMBING
J 0
(2400 3300);
DISPLAY 0.872340 (2400 3300);
PAINT GREEN (2400 3300);
DISPLAY INVISIBLE (2400 3300);
FORCEPROP 1 LAST HDL_TAP TRUE
J 0
(2725 3125);
DISPLAY 0.872340 (2725 3125);
DISPLAY INVISIBLE (2725 3125);
FORCEPROP 1 LAST PATH I146
J 0
(2398 3250);
DISPLAY 0.872340 (2398 3250);
PAINT GREEN (2398 3250);
DISPLAY INVISIBLE (2398 3250);
FORCEADD TAP..1
(2225 3300);
FORCEPROP 3 LASTPIN (2175 3300) SIG_NAME M_G_CPU0_SB_DQS_DP<9>
J 0
(2185 3310);
DISPLAY 0.659574 (2185 3310);
PAINT MONO (2185 3310);
DISPLAY INVISIBLE (2185 3310);
FORCEPROP 1 LASTPIN (2175 3300) BN 9
J 0
(2163 3308);
DISPLAY 0.680851 (2163 3308);
PAINT GREEN (2163 3308);
FORCEPROP 2 LAST CDS_LIB standard
J 0
(2225 3300);
DISPLAY INVISIBLE (2225 3300);
FORCEPROP 1 LAST BODY_TYPE PLUMBING
J 0
(2225 3350);
DISPLAY 0.872340 (2225 3350);
PAINT GREEN (2225 3350);
DISPLAY INVISIBLE (2225 3350);
FORCEPROP 1 LAST HDL_TAP TRUE
J 0
(2550 3175);
DISPLAY 0.872340 (2550 3175);
DISPLAY INVISIBLE (2550 3175);
FORCEPROP 1 LAST PATH I147
J 0
(2223 3300);
DISPLAY 0.872340 (2223 3300);
PAINT GREEN (2223 3300);
DISPLAY INVISIBLE (2223 3300);
FORCEADD TAP..1
(2225 3450);
FORCEPROP 3 LASTPIN (2175 3450) SIG_NAME M_G_CPU0_SA_DQS_DP<0>
J 0
(2185 3460);
DISPLAY 0.659574 (2185 3460);
PAINT MONO (2185 3460);
DISPLAY INVISIBLE (2185 3460);
FORCEPROP 1 LASTPIN (2175 3450) BN 0
J 0
(2163 3458);
DISPLAY 0.680851 (2163 3458);
PAINT GREEN (2163 3458);
FORCEPROP 2 LAST CDS_LIB standard
J 0
(2225 3450);
PAINT MONO (2225 3450);
DISPLAY INVISIBLE (2225 3450);
FORCEPROP 1 LAST BODY_TYPE PLUMBING
J 0
(2225 3500);
DISPLAY 0.872340 (2225 3500);
PAINT GREEN (2225 3500);
DISPLAY INVISIBLE (2225 3500);
FORCEPROP 1 LAST HDL_TAP TRUE
J 0
(2550 3325);
DISPLAY 0.872340 (2550 3325);
DISPLAY INVISIBLE (2550 3325);
FORCEPROP 1 LAST PATH I148
J 0
(2223 3450);
DISPLAY 0.872340 (2223 3450);
PAINT GREEN (2223 3450);
DISPLAY INVISIBLE (2223 3450);
FORCEADD TAP..1
(2400 3400);
FORCEPROP 3 LASTPIN (2350 3400) SIG_NAME M_G_CPU0_SA_DQS_DN<0>
J 0
(2360 3410);
DISPLAY 0.659574 (2360 3410);
PAINT MONO (2360 3410);
DISPLAY INVISIBLE (2360 3410);
FORCEPROP 1 LASTPIN (2350 3400) BN 0
J 0
(2338 3408);
DISPLAY 0.680851 (2338 3408);
PAINT GREEN (2338 3408);
FORCEPROP 2 LAST CDS_LIB standard
J 0
(2400 3400);
PAINT MONO (2400 3400);
DISPLAY INVISIBLE (2400 3400);
FORCEPROP 1 LAST BODY_TYPE PLUMBING
J 0
(2400 3450);
DISPLAY 0.872340 (2400 3450);
PAINT GREEN (2400 3450);
DISPLAY INVISIBLE (2400 3450);
FORCEPROP 1 LAST HDL_TAP TRUE
J 0
(2725 3275);
DISPLAY 0.872340 (2725 3275);
DISPLAY INVISIBLE (2725 3275);
FORCEPROP 1 LAST PATH I149
J 0
(2398 3400);
DISPLAY 0.872340 (2398 3400);
PAINT GREEN (2398 3400);
DISPLAY INVISIBLE (2398 3400);
FORCEADD OFFPAGE..1
(-3100 3050);
FORCEPROP 2 LAST $XR0 26 
J 0
(-3321 3050);
DISPLAY 0.638298 (-3321 3050);
PAINT MONO (-3321 3050);
FORCEPROP 2 LAST CDS_LIB standard
J 0
(-3100 3050);
PAINT MONO (-3100 3050);
DISPLAY INVISIBLE (-3100 3050);
FORCEPROP 1 LAST OFFPAGE TRUE
J 0
(-2775 2925);
DISPLAY 0.872340 (-2775 2925);
DISPLAY INVISIBLE (-2775 2925);
FORCEPROP 1 LAST COMMENT_BODY TRUE
J 0
(-2975 2950);
DISPLAY 0.872340 (-2975 2950);
PAINT GREEN (-2975 2950);
DISPLAY INVISIBLE (-2975 2950);
FORCEPROP 2 LAST PATH I15
J 0
(-3050 3125);
DISPLAY 1.021277 (-3050 3125);
DISPLAY INVISIBLE (-3050 3125);
FORCEADD TAP..1
(2400 3500);
FORCEPROP 3 LASTPIN (2350 3500) SIG_NAME M_G_CPU0_SA_DQS_DN<1>
J 0
(2360 3510);
DISPLAY 0.659574 (2360 3510);
PAINT MONO (2360 3510);
DISPLAY INVISIBLE (2360 3510);
FORCEPROP 1 LASTPIN (2350 3500) BN 1
J 0
(2338 3508);
DISPLAY 0.680851 (2338 3508);
PAINT GREEN (2338 3508);
FORCEPROP 2 LAST CDS_LIB standard
J 0
(2400 3500);
DISPLAY INVISIBLE (2400 3500);
FORCEPROP 1 LAST BODY_TYPE PLUMBING
J 0
(2400 3550);
DISPLAY 0.872340 (2400 3550);
PAINT GREEN (2400 3550);
DISPLAY INVISIBLE (2400 3550);
FORCEPROP 1 LAST HDL_TAP TRUE
J 0
(2725 3375);
DISPLAY 0.872340 (2725 3375);
DISPLAY INVISIBLE (2725 3375);
FORCEPROP 1 LAST PATH I150
J 0
(2398 3500);
DISPLAY 0.872340 (2398 3500);
PAINT GREEN (2398 3500);
DISPLAY INVISIBLE (2398 3500);
FORCEADD TAP..1
(2225 3650);
FORCEPROP 3 LASTPIN (2175 3650) SIG_NAME M_G_CPU0_SA_DQS_DP<2>
J 0
(2185 3660);
DISPLAY 0.659574 (2185 3660);
PAINT MONO (2185 3660);
DISPLAY INVISIBLE (2185 3660);
FORCEPROP 1 LASTPIN (2175 3650) BN 2
J 0
(2163 3658);
DISPLAY 0.680851 (2163 3658);
PAINT GREEN (2163 3658);
FORCEPROP 2 LAST CDS_LIB standard
J 0
(2225 3650);
DISPLAY INVISIBLE (2225 3650);
FORCEPROP 1 LAST BODY_TYPE PLUMBING
J 0
(2225 3700);
DISPLAY 0.872340 (2225 3700);
PAINT GREEN (2225 3700);
DISPLAY INVISIBLE (2225 3700);
FORCEPROP 1 LAST HDL_TAP TRUE
J 0
(2550 3525);
DISPLAY 0.872340 (2550 3525);
DISPLAY INVISIBLE (2550 3525);
FORCEPROP 1 LAST PATH I151
J 0
(2223 3650);
DISPLAY 0.872340 (2223 3650);
PAINT GREEN (2223 3650);
DISPLAY INVISIBLE (2223 3650);
FORCEADD TAP..1
(2225 3550);
FORCEPROP 3 LASTPIN (2175 3550) SIG_NAME M_G_CPU0_SA_DQS_DP<1>
J 0
(2185 3560);
DISPLAY 0.659574 (2185 3560);
PAINT MONO (2185 3560);
DISPLAY INVISIBLE (2185 3560);
FORCEPROP 1 LASTPIN (2175 3550) BN 1
J 0
(2163 3558);
DISPLAY 0.680851 (2163 3558);
PAINT GREEN (2163 3558);
FORCEPROP 2 LAST CDS_LIB standard
J 0
(2225 3550);
DISPLAY INVISIBLE (2225 3550);
FORCEPROP 1 LAST BODY_TYPE PLUMBING
J 0
(2225 3600);
DISPLAY 0.872340 (2225 3600);
PAINT GREEN (2225 3600);
DISPLAY INVISIBLE (2225 3600);
FORCEPROP 1 LAST HDL_TAP TRUE
J 0
(2550 3425);
DISPLAY 0.872340 (2550 3425);
DISPLAY INVISIBLE (2550 3425);
FORCEPROP 1 LAST PATH I152
J 0
(2223 3550);
DISPLAY 0.872340 (2223 3550);
PAINT GREEN (2223 3550);
DISPLAY INVISIBLE (2223 3550);
FORCEADD TAP..1
(2225 3750);
FORCEPROP 3 LASTPIN (2175 3750) SIG_NAME M_G_CPU0_SA_DQS_DP<3>
J 0
(2185 3760);
DISPLAY 0.659574 (2185 3760);
PAINT MONO (2185 3760);
DISPLAY INVISIBLE (2185 3760);
FORCEPROP 1 LASTPIN (2175 3750) BN 3
J 0
(2163 3758);
DISPLAY 0.680851 (2163 3758);
PAINT GREEN (2163 3758);
FORCEPROP 2 LAST CDS_LIB standard
J 0
(2225 3750);
PAINT MONO (2225 3750);
DISPLAY INVISIBLE (2225 3750);
FORCEPROP 1 LAST BODY_TYPE PLUMBING
J 0
(2225 3800);
DISPLAY 0.872340 (2225 3800);
PAINT GREEN (2225 3800);
DISPLAY INVISIBLE (2225 3800);
FORCEPROP 1 LAST HDL_TAP TRUE
J 0
(2550 3625);
DISPLAY 0.872340 (2550 3625);
DISPLAY INVISIBLE (2550 3625);
FORCEPROP 1 LAST PATH I153
J 0
(2223 3750);
DISPLAY 0.872340 (2223 3750);
PAINT GREEN (2223 3750);
DISPLAY INVISIBLE (2223 3750);
FORCEADD TAP..1
(2400 3600);
FORCEPROP 3 LASTPIN (2350 3600) SIG_NAME M_G_CPU0_SA_DQS_DN<2>
J 0
(2360 3610);
DISPLAY 0.659574 (2360 3610);
PAINT MONO (2360 3610);
DISPLAY INVISIBLE (2360 3610);
FORCEPROP 1 LASTPIN (2350 3600) BN 2
J 0
(2338 3608);
DISPLAY 0.680851 (2338 3608);
PAINT GREEN (2338 3608);
FORCEPROP 2 LAST CDS_LIB standard
J 0
(2400 3600);
DISPLAY INVISIBLE (2400 3600);
FORCEPROP 1 LAST BODY_TYPE PLUMBING
J 0
(2400 3650);
DISPLAY 0.872340 (2400 3650);
PAINT GREEN (2400 3650);
DISPLAY INVISIBLE (2400 3650);
FORCEPROP 1 LAST HDL_TAP TRUE
J 0
(2725 3475);
DISPLAY 0.872340 (2725 3475);
DISPLAY INVISIBLE (2725 3475);
FORCEPROP 1 LAST PATH I154
J 0
(2398 3600);
DISPLAY 0.872340 (2398 3600);
PAINT GREEN (2398 3600);
DISPLAY INVISIBLE (2398 3600);
FORCEADD TAP..1
(2400 3700);
FORCEPROP 3 LASTPIN (2350 3700) SIG_NAME M_G_CPU0_SA_DQS_DN<3>
J 0
(2360 3710);
DISPLAY 0.659574 (2360 3710);
PAINT MONO (2360 3710);
DISPLAY INVISIBLE (2360 3710);
FORCEPROP 1 LASTPIN (2350 3700) BN 3
J 0
(2338 3708);
DISPLAY 0.680851 (2338 3708);
PAINT GREEN (2338 3708);
FORCEPROP 2 LAST CDS_LIB standard
J 0
(2400 3700);
PAINT MONO (2400 3700);
DISPLAY INVISIBLE (2400 3700);
FORCEPROP 1 LAST BODY_TYPE PLUMBING
J 0
(2400 3750);
DISPLAY 0.872340 (2400 3750);
PAINT GREEN (2400 3750);
DISPLAY INVISIBLE (2400 3750);
FORCEPROP 1 LAST HDL_TAP TRUE
J 0
(2725 3575);
DISPLAY 0.872340 (2725 3575);
DISPLAY INVISIBLE (2725 3575);
FORCEPROP 1 LAST PATH I155
J 0
(2398 3700);
DISPLAY 0.872340 (2398 3700);
PAINT GREEN (2398 3700);
DISPLAY INVISIBLE (2398 3700);
FORCEADD TAP..1
(2225 3850);
FORCEPROP 3 LASTPIN (2175 3850) SIG_NAME M_G_CPU0_SA_DQS_DP<4>
J 0
(2185 3860);
DISPLAY 0.659574 (2185 3860);
PAINT MONO (2185 3860);
DISPLAY INVISIBLE (2185 3860);
FORCEPROP 1 LASTPIN (2175 3850) BN 4
J 0
(2163 3858);
DISPLAY 0.680851 (2163 3858);
PAINT GREEN (2163 3858);
FORCEPROP 2 LAST CDS_LIB standard
J 0
(2225 3850);
PAINT MONO (2225 3850);
DISPLAY INVISIBLE (2225 3850);
FORCEPROP 1 LAST BODY_TYPE PLUMBING
J 0
(2225 3900);
DISPLAY 0.872340 (2225 3900);
PAINT GREEN (2225 3900);
DISPLAY INVISIBLE (2225 3900);
FORCEPROP 1 LAST HDL_TAP TRUE
J 0
(2550 3725);
DISPLAY 0.872340 (2550 3725);
DISPLAY INVISIBLE (2550 3725);
FORCEPROP 1 LAST PATH I156
J 0
(2223 3850);
DISPLAY 0.872340 (2223 3850);
PAINT GREEN (2223 3850);
DISPLAY INVISIBLE (2223 3850);
FORCEADD TAP..1
(2225 3950);
FORCEPROP 3 LASTPIN (2175 3950) SIG_NAME M_G_CPU0_SA_DQS_DP<5>
J 0
(2185 3960);
DISPLAY 0.659574 (2185 3960);
PAINT MONO (2185 3960);
DISPLAY INVISIBLE (2185 3960);
FORCEPROP 1 LASTPIN (2175 3950) BN 5
J 0
(2163 3958);
DISPLAY 0.680851 (2163 3958);
PAINT GREEN (2163 3958);
FORCEPROP 2 LAST CDS_LIB standard
J 0
(2225 3950);
DISPLAY INVISIBLE (2225 3950);
FORCEPROP 1 LAST BODY_TYPE PLUMBING
J 0
(2225 4000);
DISPLAY 0.872340 (2225 4000);
PAINT GREEN (2225 4000);
DISPLAY INVISIBLE (2225 4000);
FORCEPROP 1 LAST HDL_TAP TRUE
J 0
(2550 3825);
DISPLAY 0.872340 (2550 3825);
DISPLAY INVISIBLE (2550 3825);
FORCEPROP 1 LAST PATH I157
J 0
(2223 3950);
DISPLAY 0.872340 (2223 3950);
PAINT GREEN (2223 3950);
DISPLAY INVISIBLE (2223 3950);
FORCEADD TAP..1
(2400 3900);
FORCEPROP 3 LASTPIN (2350 3900) SIG_NAME M_G_CPU0_SA_DQS_DN<5>
J 0
(2360 3910);
DISPLAY 0.659574 (2360 3910);
PAINT MONO (2360 3910);
DISPLAY INVISIBLE (2360 3910);
FORCEPROP 1 LASTPIN (2350 3900) BN 5
J 0
(2338 3908);
DISPLAY 0.680851 (2338 3908);
PAINT GREEN (2338 3908);
FORCEPROP 2 LAST CDS_LIB standard
J 0
(2400 3900);
DISPLAY INVISIBLE (2400 3900);
FORCEPROP 1 LAST BODY_TYPE PLUMBING
J 0
(2400 3950);
DISPLAY 0.872340 (2400 3950);
PAINT GREEN (2400 3950);
DISPLAY INVISIBLE (2400 3950);
FORCEPROP 1 LAST HDL_TAP TRUE
J 0
(2725 3775);
DISPLAY 0.872340 (2725 3775);
DISPLAY INVISIBLE (2725 3775);
FORCEPROP 1 LAST PATH I158
J 0
(2398 3900);
DISPLAY 0.872340 (2398 3900);
PAINT GREEN (2398 3900);
DISPLAY INVISIBLE (2398 3900);
FORCEADD TAP..1
(2400 3800);
FORCEPROP 3 LASTPIN (2350 3800) SIG_NAME M_G_CPU0_SA_DQS_DN<4>
J 0
(2360 3810);
DISPLAY 0.659574 (2360 3810);
PAINT MONO (2360 3810);
DISPLAY INVISIBLE (2360 3810);
FORCEPROP 1 LASTPIN (2350 3800) BN 4
J 0
(2338 3808);
DISPLAY 0.680851 (2338 3808);
PAINT GREEN (2338 3808);
FORCEPROP 2 LAST CDS_LIB standard
J 0
(2400 3800);
PAINT MONO (2400 3800);
DISPLAY INVISIBLE (2400 3800);
FORCEPROP 1 LAST BODY_TYPE PLUMBING
J 0
(2400 3850);
DISPLAY 0.872340 (2400 3850);
PAINT GREEN (2400 3850);
DISPLAY INVISIBLE (2400 3850);
FORCEPROP 1 LAST HDL_TAP TRUE
J 0
(2725 3675);
DISPLAY 0.872340 (2725 3675);
DISPLAY INVISIBLE (2725 3675);
FORCEPROP 1 LAST PATH I159
J 0
(2398 3800);
DISPLAY 0.872340 (2398 3800);
PAINT GREEN (2398 3800);
DISPLAY INVISIBLE (2398 3800);
FORCEADD VCC_CORE..1
(-3000 2225);
FORCEPROP 3 LASTPIN (-3000 2175) SIG_NAME P3V3_AUX\g
J 0
(-2990 2185);
DISPLAY 0.659574 (-2990 2185);
PAINT MONO (-2990 2185);
DISPLAY INVISIBLE (-2990 2185);
FORCEPROP 1 LAST HDL_POWER P3V3_AUX
J 1
(-3000 2275);
DISPLAY 1.148936 (-3000 2275);
PAINT GREEN (-3000 2275);
FORCEPROP 2 LAST CDS_LIB logical_power
J 0
(-3000 2225);
PAINT MONO (-3000 2225);
DISPLAY INVISIBLE (-3000 2225);
FORCEPROP 1 LAST PATH I16
J 0
(-2950 2250);
DISPLAY 0.872340 (-2950 2250);
PAINT AQUA (-2950 2250);
DISPLAY INVISIBLE (-2950 2250);
FORCEADD TAP..1
(2400 4000);
FORCEPROP 3 LASTPIN (2350 4000) SIG_NAME M_G_CPU0_SA_DQS_DN<6>
J 0
(2360 4010);
DISPLAY 0.659574 (2360 4010);
PAINT MONO (2360 4010);
DISPLAY INVISIBLE (2360 4010);
FORCEPROP 1 LASTPIN (2350 4000) BN 6
J 0
(2338 4008);
DISPLAY 0.680851 (2338 4008);
PAINT GREEN (2338 4008);
FORCEPROP 2 LAST CDS_LIB standard
J 0
(2400 4000);
DISPLAY INVISIBLE (2400 4000);
FORCEPROP 1 LAST BODY_TYPE PLUMBING
J 0
(2400 4050);
DISPLAY 0.872340 (2400 4050);
PAINT GREEN (2400 4050);
DISPLAY INVISIBLE (2400 4050);
FORCEPROP 1 LAST HDL_TAP TRUE
J 0
(2725 3875);
DISPLAY 0.872340 (2725 3875);
DISPLAY INVISIBLE (2725 3875);
FORCEPROP 1 LAST PATH I160
J 0
(2398 4000);
DISPLAY 0.872340 (2398 4000);
PAINT GREEN (2398 4000);
DISPLAY INVISIBLE (2398 4000);
FORCEADD UNIVERSAL_GND..1
(2825 100);
FORCEPROP 3 LASTPIN (2825 150) SIG_NAME GND\g
J 0
(2835 160);
DISPLAY 0.659574 (2835 160);
PAINT MONO (2835 160);
DISPLAY INVISIBLE (2835 160);
FORCEPROP 2 LAST CDS_LIB logical_power
J 0
(2825 100);
PAINT MONO (2825 100);
DISPLAY INVISIBLE (2825 100);
FORCEPROP 1 LAST HDL_POWER GND
J 1
(2850 25);
DISPLAY 0.872340 (2850 25);
PAINT GREEN (2850 25);
DISPLAY INVISIBLE (2850 25);
FORCEPROP 1 LAST PATH I161
J 0
(2900 100);
DISPLAY 0.872340 (2900 100);
PAINT AQUA (2900 100);
DISPLAY INVISIBLE (2900 100);
FORCEADD Q_CAP..1
(2825 475);
FORCEPROP 1 LAST PART_NUMBER CH6103KEA00
J 0
(2875 325);
DISPLAY 0.978723 (2875 325);
DISPLAY INVISIBLE (2875 325);
FORCEPROP 1 LAST TOLERANCE 10%
J 0
(2875 425);
DISPLAY 0.978723 (2875 425);
FORCEPROP 1 LAST VOLTAGE 16V
J 0
(2875 475);
DISPLAY 0.978723 (2875 475);
FORCEPROP 1 LAST VALUE 10UF
J 0
(2875 525);
DISPLAY 0.978723 (2875 525);
FORCEPROP 1 LAST PACK_TYPE C0805
J 0
(2875 275);
DISPLAY 0.978723 (2875 275);
FORCEPROP 1 LAST MATERIAL X6S
J 0
(2875 375);
DISPLAY 0.978723 (2875 375);
FORCEPROP 1 LAST $LOCATION C40
J 0
(2875 575);
DISPLAY 0.978723 (2875 575);
FORCEPROP 1 LASTPIN (2825 575) $PN 1
J 0
(2835 555);
DISPLAY 0.787234 (2835 555);
FORCEPROP 1 LASTPIN (2825 375) $PN 2
J 0
(2835 355);
DISPLAY 0.787234 (2835 355);
FORCEPROP 2 LAST CDS_LIB pure_quanta
J 0
(2825 475);
PAINT MONO (2825 475);
DISPLAY INVISIBLE (2825 475);
FORCEPROP 2 LAST CDS_LOCATION C40
J 0
(2875 675);
DISPLAY 1.021277 (2875 675);
DISPLAY INVISIBLE (2875 675);
FORCEPROP 2 LAST $SEC 1
J 0
(2875 675);
DISPLAY 0.680851 (2875 675);
PAINT MONO (2875 675);
DISPLAY INVISIBLE (2875 675);
FORCEPROP 2 LAST CDS_SEC 1
J 0
(2875 675);
DISPLAY 1.021277 (2875 675);
DISPLAY INVISIBLE (2875 675);
FORCEPROP 1 LAST PATH I162
J 0
(2875 625);
DISPLAY 0.978723 (2875 625);
PAINT WHITE (2875 625);
DISPLAY INVISIBLE (2875 625);
FORCEADD UNIVERSAL_GND..1
(3900 650);
FORCEPROP 3 LASTPIN (3900 700) SIG_NAME GND\g
J 0
(3910 710);
DISPLAY 0.659574 (3910 710);
PAINT MONO (3910 710);
DISPLAY INVISIBLE (3910 710);
FORCEPROP 2 LAST CDS_LIB logical_power
J 0
(3900 650);
PAINT MONO (3900 650);
DISPLAY INVISIBLE (3900 650);
FORCEPROP 1 LAST HDL_POWER GND
J 1
(3925 575);
DISPLAY 0.872340 (3925 575);
PAINT GREEN (3925 575);
DISPLAY INVISIBLE (3925 575);
FORCEPROP 1 LAST PATH I163
J 0
(3975 650);
DISPLAY 0.872340 (3975 650);
PAINT AQUA (3975 650);
DISPLAY INVISIBLE (3975 650);
FORCEADD SCONN288_ADR50017P130CC..3
(4750 2725);
FORCEPROP 1 LAST PART_NUMBER DFHST8FS461
J 0
(4295 4649);
DISPLAY 0.723404 (4295 4649);
PAINT GREEN (4295 4649);
DISPLAY INVISIBLE (4295 4649);
FORCEPROP 1 LAST MATERIAL IO
J 0
(4295 4522);
DISPLAY 0.723404 (4295 4522);
PAINT GREEN (4295 4522);
FORCEPROP 2 LAST PART_TYPE SMLF
J 0
(4300 4825);
DISPLAY 1.021277 (4300 4825);
FORCEPROP 2 LAST VALUE SCONN288_ADR50017-P130CC
J 0
(4300 4750);
DISPLAY 1.021277 (4300 4750);
FORCEPROP 1 LAST $LOCATION J13
J 0
(4300 4700);
DISPLAY 0.723404 (4300 4700);
PAINT GREEN (4300 4700);
FORCEPROP 0 LASTPIN (5350 1100) $PN G1
J 0
(5360 1110);
DISPLAY 0.680851 (5360 1110);
PAINT MONO (5360 1110);
FORCEPROP 0 LASTPIN (5350 1050) $PN G2
J 0
(5360 1060);
DISPLAY 0.680851 (5360 1060);
PAINT MONO (5360 1060);
FORCEPROP 0 LASTPIN (5350 1000) $PN G3
J 0
(5360 1010);
DISPLAY 0.680851 (5360 1010);
PAINT MONO (5360 1010);
FORCEPROP 0 LASTPIN (4150 4250) $PN 1
J 2
(4140 4260);
DISPLAY 0.680851 (4140 4260);
PAINT MONO (4140 4260);
FORCEPROP 0 LASTPIN (4150 4300) $PN 145
J 2
(4140 4310);
DISPLAY 0.680851 (4140 4310);
PAINT MONO (4140 4310);
FORCEPROP 0 LASTPIN (4150 4350) $PN 146
J 2
(4140 4360);
DISPLAY 0.680851 (4140 4360);
PAINT MONO (4140 4360);
FORCEPROP 0 LASTPIN (5350 1200) $PN 6
J 0
(5360 1210);
DISPLAY 0.680851 (5360 1210);
PAINT MONO (5360 1210);
FORCEPROP 0 LASTPIN (5350 1250) $PN 8
J 0
(5360 1260);
DISPLAY 0.680851 (5360 1260);
PAINT MONO (5360 1260);
FORCEPROP 0 LASTPIN (5350 1300) $PN 10
J 0
(5360 1310);
DISPLAY 0.680851 (5360 1310);
PAINT MONO (5360 1310);
FORCEPROP 0 LASTPIN (5350 1350) $PN 13
J 0
(5360 1360);
DISPLAY 0.680851 (5360 1360);
PAINT MONO (5360 1360);
FORCEPROP 0 LASTPIN (5350 1400) $PN 15
J 0
(5360 1410);
DISPLAY 0.680851 (5360 1410);
PAINT MONO (5360 1410);
FORCEPROP 0 LASTPIN (5350 1450) $PN 17
J 0
(5360 1460);
DISPLAY 0.680851 (5360 1460);
PAINT MONO (5360 1460);
FORCEPROP 0 LASTPIN (5350 1500) $PN 19
J 0
(5360 1510);
DISPLAY 0.680851 (5360 1510);
PAINT MONO (5360 1510);
FORCEPROP 0 LASTPIN (5350 1550) $PN 21
J 0
(5360 1560);
DISPLAY 0.680851 (5360 1560);
PAINT MONO (5360 1560);
FORCEPROP 0 LASTPIN (5350 1600) $PN 24
J 0
(5360 1610);
DISPLAY 0.680851 (5360 1610);
PAINT MONO (5360 1610);
FORCEPROP 0 LASTPIN (5350 1650) $PN 26
J 0
(5360 1660);
DISPLAY 0.680851 (5360 1660);
PAINT MONO (5360 1660);
FORCEPROP 0 LASTPIN (5350 1700) $PN 28
J 0
(5360 1710);
DISPLAY 0.680851 (5360 1710);
PAINT MONO (5360 1710);
FORCEPROP 0 LASTPIN (5350 1750) $PN 30
J 0
(5360 1760);
DISPLAY 0.680851 (5360 1760);
PAINT MONO (5360 1760);
FORCEPROP 0 LASTPIN (5350 1800) $PN 32
J 0
(5360 1810);
DISPLAY 0.680851 (5360 1810);
PAINT MONO (5360 1810);
FORCEPROP 0 LASTPIN (5350 1850) $PN 35
J 0
(5360 1860);
DISPLAY 0.680851 (5360 1860);
PAINT MONO (5360 1860);
FORCEPROP 0 LASTPIN (5350 1900) $PN 37
J 0
(5360 1910);
DISPLAY 0.680851 (5360 1910);
PAINT MONO (5360 1910);
FORCEPROP 0 LASTPIN (5350 1950) $PN 39
J 0
(5360 1960);
DISPLAY 0.680851 (5360 1960);
PAINT MONO (5360 1960);
FORCEPROP 0 LASTPIN (5350 2000) $PN 41
J 0
(5360 2010);
DISPLAY 0.680851 (5360 2010);
PAINT MONO (5360 2010);
FORCEPROP 0 LASTPIN (5350 2050) $PN 43
J 0
(5360 2060);
DISPLAY 0.680851 (5360 2060);
PAINT MONO (5360 2060);
FORCEPROP 0 LASTPIN (5350 2100) $PN 46
J 0
(5360 2110);
DISPLAY 0.680851 (5360 2110);
PAINT MONO (5360 2110);
FORCEPROP 0 LASTPIN (5350 2150) $PN 48
J 0
(5360 2160);
DISPLAY 0.680851 (5360 2160);
PAINT MONO (5360 2160);
FORCEPROP 0 LASTPIN (5350 2200) $PN 50
J 0
(5360 2210);
DISPLAY 0.680851 (5360 2210);
PAINT MONO (5360 2210);
FORCEPROP 0 LASTPIN (5350 2250) $PN 52
J 0
(5360 2260);
DISPLAY 0.680851 (5360 2260);
PAINT MONO (5360 2260);
FORCEPROP 0 LASTPIN (5350 2300) $PN 54
J 0
(5360 2310);
DISPLAY 0.680851 (5360 2310);
PAINT MONO (5360 2310);
FORCEPROP 0 LASTPIN (5350 2350) $PN 57
J 0
(5360 2360);
DISPLAY 0.680851 (5360 2360);
PAINT MONO (5360 2360);
FORCEPROP 0 LASTPIN (5350 2400) $PN 59
J 0
(5360 2410);
DISPLAY 0.680851 (5360 2410);
PAINT MONO (5360 2410);
FORCEPROP 0 LASTPIN (5350 2450) $PN 61
J 0
(5360 2460);
DISPLAY 0.680851 (5360 2460);
PAINT MONO (5360 2460);
FORCEPROP 0 LASTPIN (5350 2500) $PN 63
J 0
(5360 2510);
DISPLAY 0.680851 (5360 2510);
PAINT MONO (5360 2510);
FORCEPROP 0 LASTPIN (5350 2550) $PN 65
J 0
(5360 2560);
DISPLAY 0.680851 (5360 2560);
PAINT MONO (5360 2560);
FORCEPROP 0 LASTPIN (5350 2600) $PN 67
J 0
(5360 2610);
DISPLAY 0.680851 (5360 2610);
PAINT MONO (5360 2610);
FORCEPROP 0 LASTPIN (5350 2650) $PN 69
J 0
(5360 2660);
DISPLAY 0.680851 (5360 2660);
PAINT MONO (5360 2660);
FORCEPROP 0 LASTPIN (5350 2700) $PN 71
J 0
(5360 2710);
DISPLAY 0.680851 (5360 2710);
PAINT MONO (5360 2710);
FORCEPROP 0 LASTPIN (5350 2750) $PN 73
J 0
(5360 2760);
DISPLAY 0.680851 (5360 2760);
PAINT MONO (5360 2760);
FORCEPROP 0 LASTPIN (5350 2800) $PN 75
J 0
(5360 2810);
DISPLAY 0.680851 (5360 2810);
PAINT MONO (5360 2810);
FORCEPROP 0 LASTPIN (5350 2850) $PN 77
J 0
(5360 2860);
DISPLAY 0.680851 (5360 2860);
PAINT MONO (5360 2860);
FORCEPROP 0 LASTPIN (5350 2900) $PN 79
J 0
(5360 2910);
DISPLAY 0.680851 (5360 2910);
PAINT MONO (5360 2910);
FORCEPROP 0 LASTPIN (5350 2950) $PN 81
J 0
(5360 2960);
DISPLAY 0.680851 (5360 2960);
PAINT MONO (5360 2960);
FORCEPROP 0 LASTPIN (5350 3000) $PN 83
J 0
(5360 3010);
DISPLAY 0.680851 (5360 3010);
PAINT MONO (5360 3010);
FORCEPROP 0 LASTPIN (5350 3050) $PN 85
J 0
(5360 3060);
DISPLAY 0.680851 (5360 3060);
PAINT MONO (5360 3060);
FORCEPROP 0 LASTPIN (5350 3100) $PN 88
J 0
(5360 3110);
DISPLAY 0.680851 (5360 3110);
PAINT MONO (5360 3110);
FORCEPROP 0 LASTPIN (5350 3150) $PN 90
J 0
(5360 3160);
DISPLAY 0.680851 (5360 3160);
PAINT MONO (5360 3160);
FORCEPROP 0 LASTPIN (5350 3200) $PN 92
J 0
(5360 3210);
DISPLAY 0.680851 (5360 3210);
PAINT MONO (5360 3210);
FORCEPROP 0 LASTPIN (5350 3250) $PN 95
J 0
(5360 3260);
DISPLAY 0.680851 (5360 3260);
PAINT MONO (5360 3260);
FORCEPROP 0 LASTPIN (5350 3300) $PN 97
J 0
(5360 3310);
DISPLAY 0.680851 (5360 3310);
PAINT MONO (5360 3310);
FORCEPROP 0 LASTPIN (5350 3350) $PN 99
J 0
(5360 3360);
DISPLAY 0.680851 (5360 3360);
PAINT MONO (5360 3360);
FORCEPROP 0 LASTPIN (5350 3400) $PN 101
J 0
(5360 3410);
DISPLAY 0.680851 (5360 3410);
PAINT MONO (5360 3410);
FORCEPROP 0 LASTPIN (5350 3450) $PN 103
J 0
(5360 3460);
DISPLAY 0.680851 (5360 3460);
PAINT MONO (5360 3460);
FORCEPROP 0 LASTPIN (5350 3500) $PN 106
J 0
(5360 3510);
DISPLAY 0.680851 (5360 3510);
PAINT MONO (5360 3510);
FORCEPROP 0 LASTPIN (5350 3550) $PN 108
J 0
(5360 3560);
DISPLAY 0.680851 (5360 3560);
PAINT MONO (5360 3560);
FORCEPROP 0 LASTPIN (5350 3600) $PN 110
J 0
(5360 3610);
DISPLAY 0.680851 (5360 3610);
PAINT MONO (5360 3610);
FORCEPROP 0 LASTPIN (5350 3650) $PN 112
J 0
(5360 3660);
DISPLAY 0.680851 (5360 3660);
PAINT MONO (5360 3660);
FORCEPROP 0 LASTPIN (5350 3700) $PN 114
J 0
(5360 3710);
DISPLAY 0.680851 (5360 3710);
PAINT MONO (5360 3710);
FORCEPROP 0 LASTPIN (5350 3750) $PN 117
J 0
(5360 3760);
DISPLAY 0.680851 (5360 3760);
PAINT MONO (5360 3760);
FORCEPROP 0 LASTPIN (5350 3800) $PN 119
J 0
(5360 3810);
DISPLAY 0.680851 (5360 3810);
PAINT MONO (5360 3810);
FORCEPROP 0 LASTPIN (5350 3850) $PN 121
J 0
(5360 3860);
DISPLAY 0.680851 (5360 3860);
PAINT MONO (5360 3860);
FORCEPROP 0 LASTPIN (5350 3900) $PN 123
J 0
(5360 3910);
DISPLAY 0.680851 (5360 3910);
PAINT MONO (5360 3910);
FORCEPROP 0 LASTPIN (5350 3950) $PN 125
J 0
(5360 3960);
DISPLAY 0.680851 (5360 3960);
PAINT MONO (5360 3960);
FORCEPROP 0 LASTPIN (5350 4000) $PN 128
J 0
(5360 4010);
DISPLAY 0.680851 (5360 4010);
PAINT MONO (5360 4010);
FORCEPROP 0 LASTPIN (5350 4050) $PN 130
J 0
(5360 4060);
DISPLAY 0.680851 (5360 4060);
PAINT MONO (5360 4060);
FORCEPROP 0 LASTPIN (5350 4100) $PN 132
J 0
(5360 4110);
DISPLAY 0.680851 (5360 4110);
PAINT MONO (5360 4110);
FORCEPROP 0 LASTPIN (5350 4150) $PN 134
J 0
(5360 4160);
DISPLAY 0.680851 (5360 4160);
PAINT MONO (5360 4160);
FORCEPROP 0 LASTPIN (5350 4200) $PN 136
J 0
(5360 4210);
DISPLAY 0.680851 (5360 4210);
PAINT MONO (5360 4210);
FORCEPROP 0 LASTPIN (5350 4250) $PN 139
J 0
(5360 4260);
DISPLAY 0.680851 (5360 4260);
PAINT MONO (5360 4260);
FORCEPROP 0 LASTPIN (5350 4300) $PN 141
J 0
(5360 4310);
DISPLAY 0.680851 (5360 4310);
PAINT MONO (5360 4310);
FORCEPROP 0 LASTPIN (5350 4350) $PN 143
J 0
(5360 4360);
DISPLAY 0.680851 (5360 4360);
PAINT MONO (5360 4360);
FORCEPROP 0 LASTPIN (4150 1100) $PN 151
J 2
(4140 1110);
DISPLAY 0.680851 (4140 1110);
PAINT MONO (4140 1110);
FORCEPROP 0 LASTPIN (4150 1150) $PN 153
J 2
(4140 1160);
DISPLAY 0.680851 (4140 1160);
PAINT MONO (4140 1160);
FORCEPROP 0 LASTPIN (4150 1200) $PN 155
J 2
(4140 1210);
DISPLAY 0.680851 (4140 1210);
PAINT MONO (4140 1210);
FORCEPROP 0 LASTPIN (4150 1250) $PN 158
J 2
(4140 1260);
DISPLAY 0.680851 (4140 1260);
PAINT MONO (4140 1260);
FORCEPROP 0 LASTPIN (4150 1300) $PN 160
J 2
(4140 1310);
DISPLAY 0.680851 (4140 1310);
PAINT MONO (4140 1310);
FORCEPROP 0 LASTPIN (4150 1350) $PN 162
J 2
(4140 1360);
DISPLAY 0.680851 (4140 1360);
PAINT MONO (4140 1360);
FORCEPROP 0 LASTPIN (4150 1400) $PN 164
J 2
(4140 1410);
DISPLAY 0.680851 (4140 1410);
PAINT MONO (4140 1410);
FORCEPROP 0 LASTPIN (4150 1450) $PN 166
J 2
(4140 1460);
DISPLAY 0.680851 (4140 1460);
PAINT MONO (4140 1460);
FORCEPROP 0 LASTPIN (4150 1500) $PN 169
J 2
(4140 1510);
DISPLAY 0.680851 (4140 1510);
PAINT MONO (4140 1510);
FORCEPROP 0 LASTPIN (4150 1550) $PN 171
J 2
(4140 1560);
DISPLAY 0.680851 (4140 1560);
PAINT MONO (4140 1560);
FORCEPROP 0 LASTPIN (4150 1600) $PN 173
J 2
(4140 1610);
DISPLAY 0.680851 (4140 1610);
PAINT MONO (4140 1610);
FORCEPROP 0 LASTPIN (4150 1650) $PN 175
J 2
(4140 1660);
DISPLAY 0.680851 (4140 1660);
PAINT MONO (4140 1660);
FORCEPROP 0 LASTPIN (4150 1700) $PN 177
J 2
(4140 1710);
DISPLAY 0.680851 (4140 1710);
PAINT MONO (4140 1710);
FORCEPROP 0 LASTPIN (4150 1750) $PN 180
J 2
(4140 1760);
DISPLAY 0.680851 (4140 1760);
PAINT MONO (4140 1760);
FORCEPROP 0 LASTPIN (4150 1800) $PN 182
J 2
(4140 1810);
DISPLAY 0.680851 (4140 1810);
PAINT MONO (4140 1810);
FORCEPROP 0 LASTPIN (4150 1850) $PN 184
J 2
(4140 1860);
DISPLAY 0.680851 (4140 1860);
PAINT MONO (4140 1860);
FORCEPROP 0 LASTPIN (4150 1900) $PN 186
J 2
(4140 1910);
DISPLAY 0.680851 (4140 1910);
PAINT MONO (4140 1910);
FORCEPROP 0 LASTPIN (4150 1950) $PN 188
J 2
(4140 1960);
DISPLAY 0.680851 (4140 1960);
PAINT MONO (4140 1960);
FORCEPROP 0 LASTPIN (4150 2000) $PN 191
J 2
(4140 2010);
DISPLAY 0.680851 (4140 2010);
PAINT MONO (4140 2010);
FORCEPROP 0 LASTPIN (4150 2050) $PN 193
J 2
(4140 2060);
DISPLAY 0.680851 (4140 2060);
PAINT MONO (4140 2060);
FORCEPROP 0 LASTPIN (4150 2100) $PN 195
J 2
(4140 2110);
DISPLAY 0.680851 (4140 2110);
PAINT MONO (4140 2110);
FORCEPROP 0 LASTPIN (4150 2150) $PN 197
J 2
(4140 2160);
DISPLAY 0.680851 (4140 2160);
PAINT MONO (4140 2160);
FORCEPROP 0 LASTPIN (4150 2200) $PN 199
J 2
(4140 2210);
DISPLAY 0.680851 (4140 2210);
PAINT MONO (4140 2210);
FORCEPROP 0 LASTPIN (4150 2250) $PN 202
J 2
(4140 2260);
DISPLAY 0.680851 (4140 2260);
PAINT MONO (4140 2260);
FORCEPROP 0 LASTPIN (4150 2300) $PN 204
J 2
(4140 2310);
DISPLAY 0.680851 (4140 2310);
PAINT MONO (4140 2310);
FORCEPROP 0 LASTPIN (4150 2350) $PN 206
J 2
(4140 2360);
DISPLAY 0.680851 (4140 2360);
PAINT MONO (4140 2360);
FORCEPROP 0 LASTPIN (4150 2400) $PN 208
J 2
(4140 2410);
DISPLAY 0.680851 (4140 2410);
PAINT MONO (4140 2410);
FORCEPROP 0 LASTPIN (4150 2450) $PN 210
J 2
(4140 2460);
DISPLAY 0.680851 (4140 2460);
PAINT MONO (4140 2460);
FORCEPROP 0 LASTPIN (4150 2500) $PN 212
J 2
(4140 2510);
DISPLAY 0.680851 (4140 2510);
PAINT MONO (4140 2510);
FORCEPROP 0 LASTPIN (4150 2550) $PN 214
J 2
(4140 2560);
DISPLAY 0.680851 (4140 2560);
PAINT MONO (4140 2560);
FORCEPROP 0 LASTPIN (4150 2600) $PN 216
J 2
(4140 2610);
DISPLAY 0.680851 (4140 2610);
PAINT MONO (4140 2610);
FORCEPROP 0 LASTPIN (4150 2650) $PN 219
J 2
(4140 2660);
DISPLAY 0.680851 (4140 2660);
PAINT MONO (4140 2660);
FORCEPROP 0 LASTPIN (4150 2700) $PN 222
J 2
(4140 2710);
DISPLAY 0.680851 (4140 2710);
PAINT MONO (4140 2710);
FORCEPROP 0 LASTPIN (4150 2750) $PN 224
J 2
(4140 2760);
DISPLAY 0.680851 (4140 2760);
PAINT MONO (4140 2760);
FORCEPROP 0 LASTPIN (4150 2800) $PN 226
J 2
(4140 2810);
DISPLAY 0.680851 (4140 2810);
PAINT MONO (4140 2810);
FORCEPROP 0 LASTPIN (4150 2850) $PN 228
J 2
(4140 2860);
DISPLAY 0.680851 (4140 2860);
PAINT MONO (4140 2860);
FORCEPROP 0 LASTPIN (4150 2900) $PN 230
J 2
(4140 2910);
DISPLAY 0.680851 (4140 2910);
PAINT MONO (4140 2910);
FORCEPROP 0 LASTPIN (4150 2950) $PN 233
J 2
(4140 2960);
DISPLAY 0.680851 (4140 2960);
PAINT MONO (4140 2960);
FORCEPROP 0 LASTPIN (4150 3000) $PN 235
J 2
(4140 3010);
DISPLAY 0.680851 (4140 3010);
PAINT MONO (4140 3010);
FORCEPROP 0 LASTPIN (4150 3050) $PN 237
J 2
(4140 3060);
DISPLAY 0.680851 (4140 3060);
PAINT MONO (4140 3060);
FORCEPROP 0 LASTPIN (4150 3100) $PN 240
J 2
(4140 3110);
DISPLAY 0.680851 (4140 3110);
PAINT MONO (4140 3110);
FORCEPROP 0 LASTPIN (4150 3150) $PN 242
J 2
(4140 3160);
DISPLAY 0.680851 (4140 3160);
PAINT MONO (4140 3160);
FORCEPROP 0 LASTPIN (4150 3200) $PN 244
J 2
(4140 3210);
DISPLAY 0.680851 (4140 3210);
PAINT MONO (4140 3210);
FORCEPROP 0 LASTPIN (4150 3250) $PN 246
J 2
(4140 3260);
DISPLAY 0.680851 (4140 3260);
PAINT MONO (4140 3260);
FORCEPROP 0 LASTPIN (4150 3300) $PN 248
J 2
(4140 3310);
DISPLAY 0.680851 (4140 3310);
PAINT MONO (4140 3310);
FORCEPROP 0 LASTPIN (4150 3350) $PN 251
J 2
(4140 3360);
DISPLAY 0.680851 (4140 3360);
PAINT MONO (4140 3360);
FORCEPROP 0 LASTPIN (4150 3400) $PN 253
J 2
(4140 3410);
DISPLAY 0.680851 (4140 3410);
PAINT MONO (4140 3410);
FORCEPROP 0 LASTPIN (4150 3450) $PN 255
J 2
(4140 3460);
DISPLAY 0.680851 (4140 3460);
PAINT MONO (4140 3460);
FORCEPROP 0 LASTPIN (4150 3500) $PN 257
J 2
(4140 3510);
DISPLAY 0.680851 (4140 3510);
PAINT MONO (4140 3510);
FORCEPROP 0 LASTPIN (4150 3550) $PN 259
J 2
(4140 3560);
DISPLAY 0.680851 (4140 3560);
PAINT MONO (4140 3560);
FORCEPROP 0 LASTPIN (4150 3600) $PN 262
J 2
(4140 3610);
DISPLAY 0.680851 (4140 3610);
PAINT MONO (4140 3610);
FORCEPROP 0 LASTPIN (4150 3650) $PN 264
J 2
(4140 3660);
DISPLAY 0.680851 (4140 3660);
PAINT MONO (4140 3660);
FORCEPROP 0 LASTPIN (4150 3700) $PN 266
J 2
(4140 3710);
DISPLAY 0.680851 (4140 3710);
PAINT MONO (4140 3710);
FORCEPROP 0 LASTPIN (4150 3750) $PN 268
J 2
(4140 3760);
DISPLAY 0.680851 (4140 3760);
PAINT MONO (4140 3760);
FORCEPROP 0 LASTPIN (4150 3800) $PN 270
J 2
(4140 3810);
DISPLAY 0.680851 (4140 3810);
PAINT MONO (4140 3810);
FORCEPROP 0 LASTPIN (4150 3850) $PN 273
J 2
(4140 3860);
DISPLAY 0.680851 (4140 3860);
PAINT MONO (4140 3860);
FORCEPROP 0 LASTPIN (4150 3900) $PN 275
J 2
(4140 3910);
DISPLAY 0.680851 (4140 3910);
PAINT MONO (4140 3910);
FORCEPROP 0 LASTPIN (4150 3950) $PN 277
J 2
(4140 3960);
DISPLAY 0.680851 (4140 3960);
PAINT MONO (4140 3960);
FORCEPROP 0 LASTPIN (4150 4000) $PN 279
J 2
(4140 4010);
DISPLAY 0.680851 (4140 4010);
PAINT MONO (4140 4010);
FORCEPROP 0 LASTPIN (4150 4050) $PN 281
J 2
(4140 4060);
DISPLAY 0.680851 (4140 4060);
PAINT MONO (4140 4060);
FORCEPROP 0 LASTPIN (4150 4100) $PN 284
J 2
(4140 4110);
DISPLAY 0.680851 (4140 4110);
PAINT MONO (4140 4110);
FORCEPROP 0 LASTPIN (4150 4150) $PN 286
J 2
(4140 4160);
DISPLAY 0.680851 (4140 4160);
PAINT MONO (4140 4160);
FORCEPROP 0 LASTPIN (4150 4200) $PN 288
J 2
(4140 4210);
DISPLAY 0.680851 (4140 4210);
PAINT MONO (4140 4210);
FORCEPROP 1 LAST NEEDS_NO_SIZE TRUE
J 0
(4750 2725);
DISPLAY 0.723404 (4750 2725);
PAINT GREEN (4750 2725);
DISPLAY INVISIBLE (4750 2725);
FORCEPROP 1 LAST CDS_LMAN_SYM_OUTLINE -450,1775,450,-1775
J 0
(4750 2725);
DISPLAY 0.468085 (4750 2725);
PAINT GREEN (4750 2725);
DISPLAY INVISIBLE (4750 2725);
FORCEPROP 2 LAST CDS_LIB pure_quanta
J 0
(4750 2725);
DISPLAY INVISIBLE (4750 2725);
FORCEPROP 2 LAST CDS_LOCATION J13
J 0
(4300 4850);
DISPLAY 1.021277 (4300 4850);
DISPLAY INVISIBLE (4300 4850);
FORCEPROP 0 LAST $SEC 3
J 0
(4300 4850);
DISPLAY 0.680851 (4300 4850);
PAINT MONO (4300 4850);
DISPLAY INVISIBLE (4300 4850);
FORCEPROP 2 LAST CDS_SEC 3
J 0
(4300 4850);
DISPLAY 1.021277 (4300 4850);
DISPLAY INVISIBLE (4300 4850);
FORCEPROP 1 LAST PATH I164
J 0
(4750 2725);
DISPLAY 0.723404 (4750 2725);
PAINT GREEN (4750 2725);
DISPLAY INVISIBLE (4750 2725);
FORCEADD OFFPAGE..2
(3350 3275);
FORCEPROP 2 LAST $XR1 95 
J 0
(3629 3275);
DISPLAY 0.638298 (3629 3275);
PAINT MONO (3629 3275);
FORCEPROP 2 LAST $XR0 26 
J 0
(3539 3275);
DISPLAY 0.638298 (3539 3275);
PAINT MONO (3539 3275);
FORCEPROP 2 LAST CDS_LIB standard
J 0
(3350 3275);
PAINT MONO (3350 3275);
DISPLAY INVISIBLE (3350 3275);
FORCEPROP 1 LAST OFFPAGE TRUE
J 0
(3675 3150);
DISPLAY 1.170213 (3675 3150);
PAINT GREEN (3675 3150);
DISPLAY INVISIBLE (3675 3150);
FORCEPROP 1 LAST COMMENT_BODY TRUE
J 0
(3305 3180);
DISPLAY 1.170213 (3305 3180);
PAINT GREEN (3305 3180);
DISPLAY INVISIBLE (3305 3180);
FORCEPROP 2 LAST PATH I165
J 0
(3525 3350);
DISPLAY 1.021277 (3525 3350);
DISPLAY INVISIBLE (3525 3350);
FORCEADD OFFPAGE..2
(3350 3325);
FORCEPROP 2 LAST $XR1 95 
J 0
(3629 3325);
DISPLAY 0.638298 (3629 3325);
PAINT MONO (3629 3325);
FORCEPROP 2 LAST $XR0 26 
J 0
(3539 3325);
DISPLAY 0.638298 (3539 3325);
PAINT MONO (3539 3325);
FORCEPROP 2 LAST CDS_LIB standard
J 0
(3350 3325);
PAINT MONO (3350 3325);
DISPLAY INVISIBLE (3350 3325);
FORCEPROP 1 LAST OFFPAGE TRUE
J 0
(3675 3200);
DISPLAY 1.170213 (3675 3200);
PAINT GREEN (3675 3200);
DISPLAY INVISIBLE (3675 3200);
FORCEPROP 1 LAST COMMENT_BODY TRUE
J 0
(3305 3230);
DISPLAY 1.170213 (3305 3230);
PAINT GREEN (3305 3230);
DISPLAY INVISIBLE (3305 3230);
FORCEPROP 2 LAST PATH I166
J 0
(3525 3400);
DISPLAY 1.021277 (3525 3400);
DISPLAY INVISIBLE (3525 3400);
FORCEADD TAP..1
(2225 4150);
FORCEPROP 3 LASTPIN (2175 4150) SIG_NAME M_G_CPU0_SA_DQS_DP<7>
J 0
(2185 4160);
DISPLAY 0.659574 (2185 4160);
PAINT MONO (2185 4160);
DISPLAY INVISIBLE (2185 4160);
FORCEPROP 1 LASTPIN (2175 4150) BN 7
J 0
(2163 4158);
DISPLAY 0.680851 (2163 4158);
PAINT GREEN (2163 4158);
FORCEPROP 2 LAST CDS_LIB standard
J 0
(2225 4150);
DISPLAY INVISIBLE (2225 4150);
FORCEPROP 1 LAST BODY_TYPE PLUMBING
J 0
(2225 4200);
DISPLAY 0.872340 (2225 4200);
PAINT GREEN (2225 4200);
DISPLAY INVISIBLE (2225 4200);
FORCEPROP 1 LAST HDL_TAP TRUE
J 0
(2550 4025);
DISPLAY 0.872340 (2550 4025);
DISPLAY INVISIBLE (2550 4025);
FORCEPROP 1 LAST PATH I167
J 0
(2223 4150);
DISPLAY 0.872340 (2223 4150);
PAINT GREEN (2223 4150);
DISPLAY INVISIBLE (2223 4150);
FORCEADD TAP..1
(2225 4050);
FORCEPROP 3 LASTPIN (2175 4050) SIG_NAME M_G_CPU0_SA_DQS_DP<6>
J 0
(2185 4060);
DISPLAY 0.659574 (2185 4060);
PAINT MONO (2185 4060);
DISPLAY INVISIBLE (2185 4060);
FORCEPROP 1 LASTPIN (2175 4050) BN 6
J 0
(2163 4058);
DISPLAY 0.680851 (2163 4058);
PAINT GREEN (2163 4058);
FORCEPROP 2 LAST CDS_LIB standard
J 0
(2225 4050);
DISPLAY INVISIBLE (2225 4050);
FORCEPROP 1 LAST BODY_TYPE PLUMBING
J 0
(2225 4100);
DISPLAY 0.872340 (2225 4100);
PAINT GREEN (2225 4100);
DISPLAY INVISIBLE (2225 4100);
FORCEPROP 1 LAST HDL_TAP TRUE
J 0
(2550 3925);
DISPLAY 0.872340 (2550 3925);
DISPLAY INVISIBLE (2550 3925);
FORCEPROP 1 LAST PATH I168
J 0
(2223 4050);
DISPLAY 0.872340 (2223 4050);
PAINT GREEN (2223 4050);
DISPLAY INVISIBLE (2223 4050);
FORCEADD TAP..1
(2225 4250);
FORCEPROP 3 LASTPIN (2175 4250) SIG_NAME M_G_CPU0_SA_DQS_DP<8>
J 0
(2185 4260);
DISPLAY 0.659574 (2185 4260);
PAINT MONO (2185 4260);
DISPLAY INVISIBLE (2185 4260);
FORCEPROP 1 LASTPIN (2175 4250) BN 8
J 0
(2163 4258);
DISPLAY 0.680851 (2163 4258);
PAINT GREEN (2163 4258);
FORCEPROP 2 LAST CDS_LIB standard
J 0
(2225 4250);
DISPLAY INVISIBLE (2225 4250);
FORCEPROP 1 LAST BODY_TYPE PLUMBING
J 0
(2225 4300);
DISPLAY 0.872340 (2225 4300);
PAINT GREEN (2225 4300);
DISPLAY INVISIBLE (2225 4300);
FORCEPROP 1 LAST HDL_TAP TRUE
J 0
(2550 4125);
DISPLAY 0.872340 (2550 4125);
DISPLAY INVISIBLE (2550 4125);
FORCEPROP 1 LAST PATH I169
J 0
(2223 4250);
DISPLAY 0.872340 (2223 4250);
PAINT GREEN (2223 4250);
DISPLAY INVISIBLE (2223 4250);
FORCEADD OFFPAGE..1
(-3100 3200);
FORCEPROP 2 LAST $XR0 26 
J 0
(-3321 3200);
DISPLAY 0.638298 (-3321 3200);
PAINT MONO (-3321 3200);
FORCEPROP 2 LAST CDS_LIB standard
J 0
(-3100 3200);
PAINT MONO (-3100 3200);
DISPLAY INVISIBLE (-3100 3200);
FORCEPROP 1 LAST OFFPAGE TRUE
J 0
(-2775 3075);
DISPLAY 0.872340 (-2775 3075);
DISPLAY INVISIBLE (-2775 3075);
FORCEPROP 1 LAST COMMENT_BODY TRUE
J 0
(-2975 3100);
DISPLAY 0.872340 (-2975 3100);
PAINT GREEN (-2975 3100);
DISPLAY INVISIBLE (-2975 3100);
FORCEPROP 2 LAST PATH I17
J 0
(-3050 3275);
DISPLAY 1.021277 (-3050 3275);
DISPLAY INVISIBLE (-3050 3275);
FORCEADD TAP..1
(2400 4100);
FORCEPROP 3 LASTPIN (2350 4100) SIG_NAME M_G_CPU0_SA_DQS_DN<7>
J 0
(2360 4110);
DISPLAY 0.659574 (2360 4110);
PAINT MONO (2360 4110);
DISPLAY INVISIBLE (2360 4110);
FORCEPROP 1 LASTPIN (2350 4100) BN 7
J 0
(2338 4108);
DISPLAY 0.680851 (2338 4108);
PAINT GREEN (2338 4108);
FORCEPROP 2 LAST CDS_LIB standard
J 0
(2400 4100);
DISPLAY INVISIBLE (2400 4100);
FORCEPROP 1 LAST BODY_TYPE PLUMBING
J 0
(2400 4150);
DISPLAY 0.872340 (2400 4150);
PAINT GREEN (2400 4150);
DISPLAY INVISIBLE (2400 4150);
FORCEPROP 1 LAST HDL_TAP TRUE
J 0
(2725 3975);
DISPLAY 0.872340 (2725 3975);
DISPLAY INVISIBLE (2725 3975);
FORCEPROP 1 LAST PATH I170
J 0
(2398 4100);
DISPLAY 0.872340 (2398 4100);
PAINT GREEN (2398 4100);
DISPLAY INVISIBLE (2398 4100);
FORCEADD TAP..1
(2400 4200);
FORCEPROP 3 LASTPIN (2350 4200) SIG_NAME M_G_CPU0_SA_DQS_DN<8>
J 0
(2360 4210);
DISPLAY 0.659574 (2360 4210);
PAINT MONO (2360 4210);
DISPLAY INVISIBLE (2360 4210);
FORCEPROP 1 LASTPIN (2350 4200) BN 8
J 0
(2338 4208);
DISPLAY 0.680851 (2338 4208);
PAINT GREEN (2338 4208);
FORCEPROP 2 LAST CDS_LIB standard
J 0
(2400 4200);
DISPLAY INVISIBLE (2400 4200);
FORCEPROP 1 LAST BODY_TYPE PLUMBING
J 0
(2400 4250);
DISPLAY 0.872340 (2400 4250);
PAINT GREEN (2400 4250);
DISPLAY INVISIBLE (2400 4250);
FORCEPROP 1 LAST HDL_TAP TRUE
J 0
(2725 4075);
DISPLAY 0.872340 (2725 4075);
DISPLAY INVISIBLE (2725 4075);
FORCEPROP 1 LAST PATH I171
J 0
(2398 4200);
DISPLAY 0.872340 (2398 4200);
PAINT GREEN (2398 4200);
DISPLAY INVISIBLE (2398 4200);
FORCEADD TAP..1
(2400 4300);
FORCEPROP 3 LASTPIN (2350 4300) SIG_NAME M_G_CPU0_SA_DQS_DN<9>
J 0
(2360 4310);
DISPLAY 0.659574 (2360 4310);
PAINT MONO (2360 4310);
DISPLAY INVISIBLE (2360 4310);
FORCEPROP 1 LASTPIN (2350 4300) BN 9
J 0
(2338 4308);
DISPLAY 0.680851 (2338 4308);
PAINT GREEN (2338 4308);
FORCEPROP 2 LAST CDS_LIB standard
J 0
(2400 4300);
DISPLAY INVISIBLE (2400 4300);
FORCEPROP 1 LAST BODY_TYPE PLUMBING
J 0
(2400 4350);
DISPLAY 0.872340 (2400 4350);
PAINT GREEN (2400 4350);
DISPLAY INVISIBLE (2400 4350);
FORCEPROP 1 LAST HDL_TAP TRUE
J 0
(2725 4175);
DISPLAY 0.872340 (2725 4175);
DISPLAY INVISIBLE (2725 4175);
FORCEPROP 1 LAST PATH I172
J 0
(2398 4300);
DISPLAY 0.872340 (2398 4300);
PAINT GREEN (2398 4300);
DISPLAY INVISIBLE (2398 4300);
FORCEADD TAP..1
(2225 4350);
FORCEPROP 3 LASTPIN (2175 4350) SIG_NAME M_G_CPU0_SA_DQS_DP<9>
J 0
(2185 4360);
DISPLAY 0.659574 (2185 4360);
PAINT MONO (2185 4360);
DISPLAY INVISIBLE (2185 4360);
FORCEPROP 1 LASTPIN (2175 4350) BN 9
J 0
(2163 4358);
DISPLAY 0.680851 (2163 4358);
PAINT GREEN (2163 4358);
FORCEPROP 2 LAST CDS_LIB standard
J 0
(2225 4350);
DISPLAY INVISIBLE (2225 4350);
FORCEPROP 1 LAST BODY_TYPE PLUMBING
J 0
(2225 4400);
DISPLAY 0.872340 (2225 4400);
PAINT GREEN (2225 4400);
DISPLAY INVISIBLE (2225 4400);
FORCEPROP 1 LAST HDL_TAP TRUE
J 0
(2550 4225);
DISPLAY 0.872340 (2550 4225);
DISPLAY INVISIBLE (2550 4225);
FORCEPROP 1 LAST PATH I173
J 0
(2223 4350);
DISPLAY 0.872340 (2223 4350);
PAINT GREEN (2223 4350);
DISPLAY INVISIBLE (2223 4350);
FORCEADD OFFPAGE..2
(3350 4325);
FORCEPROP 2 LAST $XR1 95 
J 0
(3629 4325);
DISPLAY 0.638298 (3629 4325);
PAINT MONO (3629 4325);
FORCEPROP 2 LAST $XR0 26 
J 0
(3539 4325);
DISPLAY 0.638298 (3539 4325);
PAINT MONO (3539 4325);
FORCEPROP 2 LAST CDS_LIB standard
J 0
(3350 4325);
PAINT MONO (3350 4325);
DISPLAY INVISIBLE (3350 4325);
FORCEPROP 1 LAST OFFPAGE TRUE
J 0
(3675 4200);
DISPLAY 1.170213 (3675 4200);
PAINT GREEN (3675 4200);
DISPLAY INVISIBLE (3675 4200);
FORCEPROP 1 LAST COMMENT_BODY TRUE
J 0
(3305 4230);
DISPLAY 1.170213 (3305 4230);
PAINT GREEN (3305 4230);
DISPLAY INVISIBLE (3305 4230);
FORCEPROP 2 LAST PATH I174
J 0
(3525 4400);
DISPLAY 1.021277 (3525 4400);
DISPLAY INVISIBLE (3525 4400);
FORCEADD OFFPAGE..2
(3350 4375);
FORCEPROP 2 LAST $XR1 95 
J 0
(3629 4375);
DISPLAY 0.638298 (3629 4375);
PAINT MONO (3629 4375);
FORCEPROP 2 LAST $XR0 26 
J 0
(3539 4375);
DISPLAY 0.638298 (3539 4375);
PAINT MONO (3539 4375);
FORCEPROP 2 LAST CDS_LIB standard
J 0
(3350 4375);
PAINT MONO (3350 4375);
DISPLAY INVISIBLE (3350 4375);
FORCEPROP 1 LAST OFFPAGE TRUE
J 0
(3675 4250);
DISPLAY 1.170213 (3675 4250);
PAINT GREEN (3675 4250);
DISPLAY INVISIBLE (3675 4250);
FORCEPROP 1 LAST COMMENT_BODY TRUE
J 0
(3305 4280);
DISPLAY 1.170213 (3305 4280);
PAINT GREEN (3305 4280);
DISPLAY INVISIBLE (3305 4280);
FORCEPROP 2 LAST PATH I175
J 0
(3525 4450);
DISPLAY 1.021277 (3525 4450);
DISPLAY INVISIBLE (3525 4450);
FORCEADD VCC_CORE..1
(3900 4900);
FORCEPROP 3 LASTPIN (3900 4850) SIG_NAME P12V_S3_AUX_CPU0_NVDIMM\g
J 0
(3910 4860);
DISPLAY 0.659574 (3910 4860);
PAINT MONO (3910 4860);
DISPLAY INVISIBLE (3910 4860);
FORCEPROP 1 LAST HDL_POWER P12V_S3_AUX_CPU0_NVDIMM
J 1
(3900 4950);
DISPLAY 1.148936 (3900 4950);
PAINT GREEN (3900 4950);
FORCEPROP 2 LAST CDS_LIB logical_power
J 0
(3900 4900);
PAINT MONO (3900 4900);
DISPLAY INVISIBLE (3900 4900);
FORCEPROP 1 LAST PATH I176
J 0
(3950 4925);
DISPLAY 0.872340 (3950 4925);
PAINT AQUA (3950 4925);
DISPLAY INVISIBLE (3950 4925);
FORCEADD UNIVERSAL_GND..1
(5600 650);
FORCEPROP 3 LASTPIN (5600 700) SIG_NAME GND\g
J 0
(5610 710);
DISPLAY 0.659574 (5610 710);
PAINT MONO (5610 710);
DISPLAY INVISIBLE (5610 710);
FORCEPROP 2 LAST CDS_LIB logical_power
J 0
(5600 650);
PAINT MONO (5600 650);
DISPLAY INVISIBLE (5600 650);
FORCEPROP 1 LAST HDL_POWER GND
J 1
(5625 575);
DISPLAY 0.872340 (5625 575);
PAINT GREEN (5625 575);
DISPLAY INVISIBLE (5625 575);
FORCEPROP 1 LAST PATH I177
J 0
(5675 650);
DISPLAY 0.872340 (5675 650);
PAINT AQUA (5675 650);
DISPLAY INVISIBLE (5675 650);
FORCEADD SCONN288_ADR50017P130CC..2
(1325 3350);
FORCEPROP 1 LAST PART_NUMBER DFHST8FS461
J 0
(732 4650);
DISPLAY 0.723404 (732 4650);
PAINT GREEN (732 4650);
DISPLAY INVISIBLE (732 4650);
FORCEPROP 1 LAST MATERIAL IO
J 0
(732 4523);
DISPLAY 0.723404 (732 4523);
PAINT GREEN (732 4523);
FORCEPROP 2 LAST VALUE SCONN288_ADR50017-P130CC
J 0
(743 4753);
DISPLAY 1.021277 (743 4753);
FORCEPROP 2 LAST PART_TYPE SMLF
J 0
(743 4803);
DISPLAY 1.021277 (743 4803);
FORCEPROP 1 LAST LOCATION J13
J 0
(725 4700);
DISPLAY 0.723404 (725 4700);
PAINT GREEN (725 4700);
FORCEPROP 0 LASTPIN (2075 3400) $PN 12
J 0
(2085 3410);
DISPLAY 0.680851 (2085 3410);
PAINT MONO (2085 3410);
FORCEPROP 0 LASTPIN (2075 3450) $PN 11
J 0
(2085 3460);
DISPLAY 0.680851 (2085 3460);
PAINT MONO (2085 3460);
FORCEPROP 0 LASTPIN (2075 2350) $PN 105
J 0
(2085 2360);
DISPLAY 0.680851 (2085 2360);
PAINT MONO (2085 2360);
FORCEPROP 0 LASTPIN (2075 2400) $PN 104
J 0
(2085 2410);
DISPLAY 0.680851 (2085 2410);
PAINT MONO (2085 2410);
FORCEPROP 0 LASTPIN (2075 3500) $PN 23
J 0
(2085 3510);
DISPLAY 0.680851 (2085 3510);
PAINT MONO (2085 3510);
FORCEPROP 0 LASTPIN (2075 3550) $PN 22
J 0
(2085 3560);
DISPLAY 0.680851 (2085 3560);
PAINT MONO (2085 3560);
FORCEPROP 0 LASTPIN (2075 2450) $PN 116
J 0
(2085 2460);
DISPLAY 0.680851 (2085 2460);
PAINT MONO (2085 2460);
FORCEPROP 0 LASTPIN (2075 2500) $PN 115
J 0
(2085 2510);
DISPLAY 0.680851 (2085 2510);
PAINT MONO (2085 2510);
FORCEPROP 0 LASTPIN (2075 3600) $PN 34
J 0
(2085 3610);
DISPLAY 0.680851 (2085 3610);
PAINT MONO (2085 3610);
FORCEPROP 0 LASTPIN (2075 3650) $PN 33
J 0
(2085 3660);
DISPLAY 0.680851 (2085 3660);
PAINT MONO (2085 3660);
FORCEPROP 0 LASTPIN (2075 2550) $PN 127
J 0
(2085 2560);
DISPLAY 0.680851 (2085 2560);
PAINT MONO (2085 2560);
FORCEPROP 0 LASTPIN (2075 2600) $PN 126
J 0
(2085 2610);
DISPLAY 0.680851 (2085 2610);
PAINT MONO (2085 2610);
FORCEPROP 0 LASTPIN (2075 3700) $PN 45
J 0
(2085 3710);
DISPLAY 0.680851 (2085 3710);
PAINT MONO (2085 3710);
FORCEPROP 0 LASTPIN (2075 3750) $PN 44
J 0
(2085 3760);
DISPLAY 0.680851 (2085 3760);
PAINT MONO (2085 3760);
FORCEPROP 0 LASTPIN (2075 2650) $PN 138
J 0
(2085 2660);
DISPLAY 0.680851 (2085 2660);
PAINT MONO (2085 2660);
FORCEPROP 0 LASTPIN (2075 2700) $PN 137
J 0
(2085 2710);
DISPLAY 0.680851 (2085 2710);
PAINT MONO (2085 2710);
FORCEPROP 0 LASTPIN (2075 3800) $PN 56
J 0
(2085 3810);
DISPLAY 0.680851 (2085 3810);
PAINT MONO (2085 3810);
FORCEPROP 0 LASTPIN (2075 3850) $PN 55
J 0
(2085 3860);
DISPLAY 0.680851 (2085 3860);
PAINT MONO (2085 3860);
FORCEPROP 0 LASTPIN (2075 2750) $PN 238
J 0
(2085 2760);
DISPLAY 0.680851 (2085 2760);
PAINT MONO (2085 2760);
FORCEPROP 0 LASTPIN (2075 2800) $PN 239
J 0
(2085 2810);
DISPLAY 0.680851 (2085 2810);
PAINT MONO (2085 2810);
FORCEPROP 0 LASTPIN (2075 3900) $PN 156
J 0
(2085 3910);
DISPLAY 0.680851 (2085 3910);
PAINT MONO (2085 3910);
FORCEPROP 0 LASTPIN (2075 3950) $PN 157
J 0
(2085 3960);
DISPLAY 0.680851 (2085 3960);
PAINT MONO (2085 3960);
FORCEPROP 0 LASTPIN (2075 2850) $PN 249
J 0
(2085 2860);
DISPLAY 0.680851 (2085 2860);
PAINT MONO (2085 2860);
FORCEPROP 0 LASTPIN (2075 2900) $PN 250
J 0
(2085 2910);
DISPLAY 0.680851 (2085 2910);
PAINT MONO (2085 2910);
FORCEPROP 0 LASTPIN (2075 4000) $PN 167
J 0
(2085 4010);
DISPLAY 0.680851 (2085 4010);
PAINT MONO (2085 4010);
FORCEPROP 0 LASTPIN (2075 4050) $PN 168
J 0
(2085 4060);
DISPLAY 0.680851 (2085 4060);
PAINT MONO (2085 4060);
FORCEPROP 0 LASTPIN (2075 2950) $PN 260
J 0
(2085 2960);
DISPLAY 0.680851 (2085 2960);
PAINT MONO (2085 2960);
FORCEPROP 0 LASTPIN (2075 3000) $PN 261
J 0
(2085 3010);
DISPLAY 0.680851 (2085 3010);
PAINT MONO (2085 3010);
FORCEPROP 0 LASTPIN (2075 4100) $PN 178
J 0
(2085 4110);
DISPLAY 0.680851 (2085 4110);
PAINT MONO (2085 4110);
FORCEPROP 0 LASTPIN (2075 4150) $PN 179
J 0
(2085 4160);
DISPLAY 0.680851 (2085 4160);
PAINT MONO (2085 4160);
FORCEPROP 0 LASTPIN (2075 3050) $PN 271
J 0
(2085 3060);
DISPLAY 0.680851 (2085 3060);
PAINT MONO (2085 3060);
FORCEPROP 0 LASTPIN (2075 3100) $PN 272
J 0
(2085 3110);
DISPLAY 0.680851 (2085 3110);
PAINT MONO (2085 3110);
FORCEPROP 0 LASTPIN (2075 4200) $PN 189
J 0
(2085 4210);
DISPLAY 0.680851 (2085 4210);
PAINT MONO (2085 4210);
FORCEPROP 0 LASTPIN (2075 4250) $PN 190
J 0
(2085 4260);
DISPLAY 0.680851 (2085 4260);
PAINT MONO (2085 4260);
FORCEPROP 0 LASTPIN (2075 3150) $PN 282
J 0
(2085 3160);
DISPLAY 0.680851 (2085 3160);
PAINT MONO (2085 3160);
FORCEPROP 0 LASTPIN (2075 3200) $PN 283
J 0
(2085 3210);
DISPLAY 0.680851 (2085 3210);
PAINT MONO (2085 3210);
FORCEPROP 0 LASTPIN (2075 4300) $PN 200
J 0
(2085 4310);
DISPLAY 0.680851 (2085 4310);
PAINT MONO (2085 4310);
FORCEPROP 0 LASTPIN (2075 4350) $PN 201
J 0
(2085 4360);
DISPLAY 0.680851 (2085 4360);
PAINT MONO (2085 4360);
FORCEPROP 0 LASTPIN (2075 3250) $PN 94
J 0
(2085 3260);
DISPLAY 0.680851 (2085 3260);
PAINT MONO (2085 3260);
FORCEPROP 0 LASTPIN (2075 3300) $PN 93
J 0
(2085 3310);
DISPLAY 0.680851 (2085 3310);
PAINT MONO (2085 3310);
FORCEPROP 1 LAST NEEDS_NO_SIZE TRUE
J 0
(1325 3350);
DISPLAY 0.723404 (1325 3350);
PAINT GREEN (1325 3350);
DISPLAY INVISIBLE (1325 3350);
FORCEPROP 1 LAST CDS_LMAN_SYM_OUTLINE -600,1150,600,-1150
J 0
(1325 3350);
DISPLAY 0.468085 (1325 3350);
PAINT GREEN (1325 3350);
DISPLAY INVISIBLE (1325 3350);
FORCEPROP 2 LAST CDS_LIB pure_quanta
J 0
(1325 3350);
DISPLAY INVISIBLE (1325 3350);
FORCEPROP 0 LAST $SEC 2
J 0
(750 4875);
DISPLAY 0.680851 (750 4875);
PAINT MONO (750 4875);
DISPLAY INVISIBLE (750 4875);
FORCEPROP 0 LAST CDS_SEC 2
J 0
(750 4875);
DISPLAY 1.021277 (750 4875);
DISPLAY INVISIBLE (750 4875);
FORCEPROP 1 LAST PATH I178
J 0
(1325 3350);
DISPLAY 0.723404 (1325 3350);
PAINT GREEN (1325 3350);
DISPLAY INVISIBLE (1325 3350);
FORCEADD Q_RES..1
(-3150 1650);
FORCEPROP 1 LAST PART_NUMBER CS04992FB07
J 0
(-3050 1625);
DISPLAY 0.404255 (-3050 1625);
DISPLAY INVISIBLE (-3050 1625);
FORCEPROP 1 LAST VALUE 49.9
J 2
(-2925 1650);
DISPLAY 0.510638 (-2925 1650);
FORCEPROP 1 LAST MATERIAL CHIP
J 0
(-3375 1625);
DISPLAY 0.404255 (-3375 1625);
FORCEPROP 1 LAST $LOCATION R3887
J 0
(-3400 1650);
DISPLAY 0.638298 (-3400 1650);
FORCEPROP 1 LASTPIN (-3250 1650) $PN 1
J 0
(-3238 1662);
DISPLAY 0.787234 (-3238 1662);
PAINT MONO (-3238 1662);
FORCEPROP 1 LASTPIN (-3050 1650) $PN 2
J 0
(-3088 1662);
DISPLAY 0.787234 (-3088 1662);
PAINT MONO (-3088 1662);
FORCEPROP 2 LAST CDS_LIB pure_quanta
J 0
(-3150 1650);
DISPLAY INVISIBLE (-3150 1650);
FORCEPROP 1 LAST PACK_TYPE 0402LF
J 0
(-2850 1650);
DISPLAY 0.510638 (-2850 1650);
DISPLAY INVISIBLE (-2850 1650);
FORCEPROP 1 LAST TOLERANCE 1%
J 0
(-2925 1650);
DISPLAY 0.510638 (-2925 1650);
DISPLAY INVISIBLE (-2925 1650);
FORCEPROP 1 LAST WATTAGE 1/16W
J 2
(-2850 1600);
DISPLAY 0.404255 (-2850 1600);
DISPLAY INVISIBLE (-2850 1600);
FORCEPROP 0 LAST CDS_LOCATION R3887
J 0
(-3300 1700);
DISPLAY 1.021277 (-3300 1700);
DISPLAY INVISIBLE (-3300 1700);
FORCEPROP 0 LAST $SEC 1
J 0
(-3300 1700);
DISPLAY 0.680851 (-3300 1700);
PAINT MONO (-3300 1700);
DISPLAY INVISIBLE (-3300 1700);
FORCEPROP 0 LAST CDS_SEC 1
J 0
(-3300 1700);
DISPLAY 1.021277 (-3300 1700);
DISPLAY INVISIBLE (-3300 1700);
FORCEPROP 1 LAST PATH I179
J 0
(-3200 1800);
DISPLAY 0.978723 (-3200 1800);
PAINT WHITE (-3200 1800);
DISPLAY INVISIBLE (-3200 1800);
FORCEADD OFFPAGE..1
(-3100 3250);
FORCEPROP 2 LAST $XR0 26 
J 0
(-3321 3250);
DISPLAY 0.638298 (-3321 3250);
PAINT MONO (-3321 3250);
FORCEPROP 2 LAST CDS_LIB standard
J 0
(-3100 3250);
PAINT MONO (-3100 3250);
DISPLAY INVISIBLE (-3100 3250);
FORCEPROP 1 LAST OFFPAGE TRUE
J 0
(-2775 3125);
DISPLAY 0.872340 (-2775 3125);
DISPLAY INVISIBLE (-2775 3125);
FORCEPROP 1 LAST COMMENT_BODY TRUE
J 0
(-2975 3150);
DISPLAY 0.872340 (-2975 3150);
PAINT GREEN (-2975 3150);
DISPLAY INVISIBLE (-2975 3150);
FORCEPROP 2 LAST PATH I18
J 0
(-3050 3325);
DISPLAY 1.021277 (-3050 3325);
DISPLAY INVISIBLE (-3050 3325);
FORCEADD OFFPAGE..1
(-1950 1600);
FORCEPROP 2 LAST $XR7 97 
J 0
(-2832 1600);
DISPLAY 0.638298 (-2832 1600);
PAINT MONO (-2832 1600);
FORCEPROP 2 LAST $XR6 96 
J 0
(-2742 1600);
DISPLAY 0.638298 (-2742 1600);
PAINT MONO (-2742 1600);
FORCEPROP 2 LAST $XR5 95 
J 0
(-2652 1600);
DISPLAY 0.638298 (-2652 1600);
PAINT MONO (-2652 1600);
FORCEPROP 2 LAST $XR4 93 
J 0
(-2562 1600);
DISPLAY 0.638298 (-2562 1600);
PAINT MONO (-2562 1600);
FORCEPROP 2 LAST $XR3 92 
J 0
(-2472 1600);
DISPLAY 0.638298 (-2472 1600);
PAINT MONO (-2472 1600);
FORCEPROP 2 LAST $XR2 91 
J 0
(-2382 1600);
DISPLAY 0.638298 (-2382 1600);
PAINT MONO (-2382 1600);
FORCEPROP 2 LAST $XR1 90 
J 0
(-2292 1600);
DISPLAY 0.638298 (-2292 1600);
PAINT MONO (-2292 1600);
FORCEPROP 2 LAST $XR0 229 
J 0
(-2202 1600);
DISPLAY 0.638298 (-2202 1600);
PAINT MONO (-2202 1600);
FORCEPROP 2 LAST CDS_LIB standard
J 2
(-1950 1600);
DISPLAY INVISIBLE (-1950 1600);
FORCEPROP 1 LAST OFFPAGE TRUE
J 0
(-1625 1475);
DISPLAY 0.872340 (-1625 1475);
DISPLAY INVISIBLE (-1625 1475);
FORCEPROP 1 LAST COMMENT_BODY TRUE
J 0
(-1825 1500);
DISPLAY 0.872340 (-1825 1500);
PAINT GREEN (-1825 1500);
DISPLAY INVISIBLE (-1825 1500);
FORCEPROP 2 LAST PATH I180
J 2
(-2125 1675);
DISPLAY 1.021277 (-2125 1675);
DISPLAY INVISIBLE (-2125 1675);
FORCEADD OFFPAGE..1
(-3100 3100);
FORCEPROP 2 LAST $XR0 26 
J 0
(-3321 3100);
DISPLAY 0.638298 (-3321 3100);
PAINT MONO (-3321 3100);
FORCEPROP 2 LAST CDS_LIB standard
J 0
(-3100 3100);
PAINT MONO (-3100 3100);
DISPLAY INVISIBLE (-3100 3100);
FORCEPROP 1 LAST OFFPAGE TRUE
J 0
(-2775 2975);
DISPLAY 0.872340 (-2775 2975);
DISPLAY INVISIBLE (-2775 2975);
FORCEPROP 1 LAST COMMENT_BODY TRUE
J 0
(-2975 3000);
DISPLAY 0.872340 (-2975 3000);
PAINT GREEN (-2975 3000);
DISPLAY INVISIBLE (-2975 3000);
FORCEPROP 2 LAST PATH I19
J 0
(-3050 3175);
DISPLAY 1.021277 (-3050 3175);
DISPLAY INVISIBLE (-3050 3175);
FORCEADD OFFPAGE..2
R 2
(-3100 900);
FORCEPROP 2 LAST $XR0 26 
J 0
(-3324 900);
DISPLAY 0.638298 (-3324 900);
PAINT MONO (-3324 900);
FORCEPROP 2 LAST CDS_LIB standard
J 0
(-3100 900);
PAINT MONO (-3100 900);
DISPLAY INVISIBLE (-3100 900);
FORCEPROP 1 LAST OFFPAGE TRUE
J 2
(-3425 775);
DISPLAY 0.872340 (-3425 775);
DISPLAY INVISIBLE (-3425 775);
FORCEPROP 1 LAST COMMENT_BODY TRUE
J 2
(-3055 805);
DISPLAY 0.872340 (-3055 805);
PAINT GREEN (-3055 805);
DISPLAY INVISIBLE (-3055 805);
FORCEPROP 2 LAST PATH I2
J 0
(-3050 975);
DISPLAY 1.021277 (-3050 975);
DISPLAY INVISIBLE (-3050 975);
FORCEADD OFFPAGE..1
(-3100 3500);
FORCEPROP 2 LAST $XR1 95 
J 0
(-3411 3500);
DISPLAY 0.638298 (-3411 3500);
PAINT MONO (-3411 3500);
FORCEPROP 2 LAST $XR0 26 
J 0
(-3321 3500);
DISPLAY 0.638298 (-3321 3500);
PAINT MONO (-3321 3500);
FORCEPROP 2 LAST CDS_LIB standard
J 0
(-3100 3500);
PAINT MONO (-3100 3500);
DISPLAY INVISIBLE (-3100 3500);
FORCEPROP 1 LAST OFFPAGE TRUE
J 0
(-2775 3375);
DISPLAY 0.872340 (-2775 3375);
DISPLAY INVISIBLE (-2775 3375);
FORCEPROP 1 LAST COMMENT_BODY TRUE
J 0
(-2975 3400);
DISPLAY 0.872340 (-2975 3400);
PAINT GREEN (-2975 3400);
DISPLAY INVISIBLE (-2975 3400);
FORCEPROP 2 LAST PATH I20
J 0
(-3050 3575);
DISPLAY 1.021277 (-3050 3575);
DISPLAY INVISIBLE (-3050 3575);
FORCEADD OFFPAGE..1
(-3100 3400);
FORCEPROP 2 LAST $XR0 26 
J 0
(-3321 3400);
DISPLAY 0.638298 (-3321 3400);
PAINT MONO (-3321 3400);
FORCEPROP 2 LAST CDS_LIB standard
J 0
(-3100 3400);
PAINT MONO (-3100 3400);
DISPLAY INVISIBLE (-3100 3400);
FORCEPROP 1 LAST OFFPAGE TRUE
J 0
(-2775 3275);
DISPLAY 0.872340 (-2775 3275);
DISPLAY INVISIBLE (-2775 3275);
FORCEPROP 1 LAST COMMENT_BODY TRUE
J 0
(-2975 3300);
DISPLAY 0.872340 (-2975 3300);
PAINT GREEN (-2975 3300);
DISPLAY INVISIBLE (-2975 3300);
FORCEPROP 2 LAST PATH I21
J 0
(-3050 3475);
DISPLAY 1.021277 (-3050 3475);
DISPLAY INVISIBLE (-3050 3475);
FORCEADD OFFPAGE..1
(-3100 3350);
FORCEPROP 2 LAST $XR0 26 
J 0
(-3321 3350);
DISPLAY 0.638298 (-3321 3350);
PAINT MONO (-3321 3350);
FORCEPROP 2 LAST CDS_LIB standard
J 0
(-3100 3350);
PAINT MONO (-3100 3350);
DISPLAY INVISIBLE (-3100 3350);
FORCEPROP 1 LAST OFFPAGE TRUE
J 0
(-2775 3225);
DISPLAY 0.872340 (-2775 3225);
DISPLAY INVISIBLE (-2775 3225);
FORCEPROP 1 LAST COMMENT_BODY TRUE
J 0
(-2975 3250);
DISPLAY 0.872340 (-2975 3250);
PAINT GREEN (-2975 3250);
DISPLAY INVISIBLE (-2975 3250);
FORCEPROP 2 LAST PATH I22
J 0
(-3050 3425);
DISPLAY 1.021277 (-3050 3425);
DISPLAY INVISIBLE (-3050 3425);
FORCEADD OFFPAGE..1
(-3100 3550);
FORCEPROP 2 LAST $XR1 95 
J 0
(-3411 3550);
DISPLAY 0.638298 (-3411 3550);
PAINT MONO (-3411 3550);
FORCEPROP 2 LAST $XR0 26 
J 0
(-3321 3550);
DISPLAY 0.638298 (-3321 3550);
PAINT MONO (-3321 3550);
FORCEPROP 2 LAST CDS_LIB standard
J 0
(-3100 3550);
PAINT MONO (-3100 3550);
DISPLAY INVISIBLE (-3100 3550);
FORCEPROP 1 LAST OFFPAGE TRUE
J 0
(-2775 3425);
DISPLAY 0.872340 (-2775 3425);
DISPLAY INVISIBLE (-2775 3425);
FORCEPROP 1 LAST COMMENT_BODY TRUE
J 0
(-2975 3450);
DISPLAY 0.872340 (-2975 3450);
PAINT GREEN (-2975 3450);
DISPLAY INVISIBLE (-2975 3450);
FORCEPROP 2 LAST PATH I23
J 0
(-3050 3625);
DISPLAY 1.021277 (-3050 3625);
DISPLAY INVISIBLE (-3050 3625);
FORCEADD OFFPAGE..1
(-3100 3975);
FORCEPROP 2 LAST $XR1 95 
J 0
(-3411 3975);
DISPLAY 0.638298 (-3411 3975);
PAINT MONO (-3411 3975);
FORCEPROP 2 LAST $XR0 26 
J 0
(-3321 3975);
DISPLAY 0.638298 (-3321 3975);
PAINT MONO (-3321 3975);
FORCEPROP 2 LAST CDS_LIB standard
J 0
(-3100 3975);
PAINT MONO (-3100 3975);
DISPLAY INVISIBLE (-3100 3975);
FORCEPROP 1 LAST OFFPAGE TRUE
J 0
(-2775 3850);
DISPLAY 0.872340 (-2775 3850);
DISPLAY INVISIBLE (-2775 3850);
FORCEPROP 1 LAST COMMENT_BODY TRUE
J 0
(-2975 3875);
DISPLAY 0.872340 (-2975 3875);
PAINT GREEN (-2975 3875);
DISPLAY INVISIBLE (-2975 3875);
FORCEPROP 2 LAST PATH I24
J 0
(-3050 4050);
DISPLAY 1.021277 (-3050 4050);
DISPLAY INVISIBLE (-3050 4050);
FORCEADD TAP..1
R 2
(-2175 2150);
FORCEPROP 3 LASTPIN (-2125 2150) SIG_NAME M_G_CPU0_SB_CB<0>
J 0
(-2115 2160);
DISPLAY 0.659574 (-2115 2160);
PAINT MONO (-2115 2160);
DISPLAY INVISIBLE (-2115 2160);
FORCEPROP 1 LASTPIN (-2125 2150) BN 0
J 2
(-2113 2158);
DISPLAY 0.680851 (-2113 2158);
PAINT GREEN (-2113 2158);
FORCEPROP 2 LAST CDS_LIB standard
J 0
(-2175 2150);
PAINT MONO (-2175 2150);
DISPLAY INVISIBLE (-2175 2150);
FORCEPROP 1 LAST BODY_TYPE PLUMBING
J 2
(-2175 2200);
DISPLAY 0.872340 (-2175 2200);
PAINT GREEN (-2175 2200);
DISPLAY INVISIBLE (-2175 2200);
FORCEPROP 1 LAST HDL_TAP TRUE
J 2
(-2500 2025);
DISPLAY 0.872340 (-2500 2025);
DISPLAY INVISIBLE (-2500 2025);
FORCEPROP 1 LAST PATH I25
J 2
(-2173 2150);
DISPLAY 0.872340 (-2173 2150);
PAINT GREEN (-2173 2150);
DISPLAY INVISIBLE (-2173 2150);
FORCEADD TAP..1
R 2
(-2175 2200);
FORCEPROP 3 LASTPIN (-2125 2200) SIG_NAME M_G_CPU0_SB_CB<1>
J 0
(-2115 2210);
DISPLAY 0.659574 (-2115 2210);
PAINT MONO (-2115 2210);
DISPLAY INVISIBLE (-2115 2210);
FORCEPROP 1 LASTPIN (-2125 2200) BN 1
J 2
(-2113 2208);
DISPLAY 0.680851 (-2113 2208);
PAINT GREEN (-2113 2208);
FORCEPROP 2 LAST CDS_LIB standard
J 0
(-2175 2200);
DISPLAY INVISIBLE (-2175 2200);
FORCEPROP 1 LAST BODY_TYPE PLUMBING
J 2
(-2175 2250);
DISPLAY 0.872340 (-2175 2250);
PAINT GREEN (-2175 2250);
DISPLAY INVISIBLE (-2175 2250);
FORCEPROP 1 LAST HDL_TAP TRUE
J 2
(-2500 2075);
DISPLAY 0.872340 (-2500 2075);
DISPLAY INVISIBLE (-2500 2075);
FORCEPROP 1 LAST PATH I26
J 2
(-2173 2200);
DISPLAY 0.872340 (-2173 2200);
PAINT GREEN (-2173 2200);
DISPLAY INVISIBLE (-2173 2200);
FORCEADD TAP..1
R 2
(-2175 2250);
FORCEPROP 3 LASTPIN (-2125 2250) SIG_NAME M_G_CPU0_SB_CB<2>
J 0
(-2115 2260);
DISPLAY 0.659574 (-2115 2260);
PAINT MONO (-2115 2260);
DISPLAY INVISIBLE (-2115 2260);
FORCEPROP 1 LASTPIN (-2125 2250) BN 2
J 2
(-2113 2258);
DISPLAY 0.680851 (-2113 2258);
PAINT GREEN (-2113 2258);
FORCEPROP 2 LAST CDS_LIB standard
J 0
(-2175 2250);
DISPLAY INVISIBLE (-2175 2250);
FORCEPROP 1 LAST BODY_TYPE PLUMBING
J 2
(-2175 2300);
DISPLAY 0.872340 (-2175 2300);
PAINT GREEN (-2175 2300);
DISPLAY INVISIBLE (-2175 2300);
FORCEPROP 1 LAST HDL_TAP TRUE
J 2
(-2500 2125);
DISPLAY 0.872340 (-2500 2125);
DISPLAY INVISIBLE (-2500 2125);
FORCEPROP 1 LAST PATH I27
J 2
(-2173 2250);
DISPLAY 0.872340 (-2173 2250);
PAINT GREEN (-2173 2250);
DISPLAY INVISIBLE (-2173 2250);
FORCEADD TAP..1
R 2
(-2175 2300);
FORCEPROP 3 LASTPIN (-2125 2300) SIG_NAME M_G_CPU0_SB_CB<3>
J 0
(-2115 2310);
DISPLAY 0.659574 (-2115 2310);
PAINT MONO (-2115 2310);
DISPLAY INVISIBLE (-2115 2310);
FORCEPROP 1 LASTPIN (-2125 2300) BN 3
J 2
(-2113 2308);
DISPLAY 0.680851 (-2113 2308);
PAINT GREEN (-2113 2308);
FORCEPROP 2 LAST CDS_LIB standard
J 0
(-2175 2300);
DISPLAY INVISIBLE (-2175 2300);
FORCEPROP 1 LAST BODY_TYPE PLUMBING
J 2
(-2175 2350);
DISPLAY 0.872340 (-2175 2350);
PAINT GREEN (-2175 2350);
DISPLAY INVISIBLE (-2175 2350);
FORCEPROP 1 LAST HDL_TAP TRUE
J 2
(-2500 2175);
DISPLAY 0.872340 (-2500 2175);
DISPLAY INVISIBLE (-2500 2175);
FORCEPROP 1 LAST PATH I28
J 2
(-2173 2300);
DISPLAY 0.872340 (-2173 2300);
PAINT GREEN (-2173 2300);
DISPLAY INVISIBLE (-2173 2300);
FORCEADD TAP..1
R 2
(-2175 2350);
FORCEPROP 3 LASTPIN (-2125 2350) SIG_NAME M_G_CPU0_SB_CB<4>
J 0
(-2115 2360);
DISPLAY 0.659574 (-2115 2360);
PAINT MONO (-2115 2360);
DISPLAY INVISIBLE (-2115 2360);
FORCEPROP 1 LASTPIN (-2125 2350) BN 4
J 2
(-2113 2358);
DISPLAY 0.680851 (-2113 2358);
PAINT GREEN (-2113 2358);
FORCEPROP 2 LAST CDS_LIB standard
J 0
(-2175 2350);
DISPLAY INVISIBLE (-2175 2350);
FORCEPROP 1 LAST BODY_TYPE PLUMBING
J 2
(-2175 2400);
DISPLAY 0.872340 (-2175 2400);
PAINT GREEN (-2175 2400);
DISPLAY INVISIBLE (-2175 2400);
FORCEPROP 1 LAST HDL_TAP TRUE
J 2
(-2500 2225);
DISPLAY 0.872340 (-2500 2225);
DISPLAY INVISIBLE (-2500 2225);
FORCEPROP 1 LAST PATH I29
J 2
(-2173 2350);
DISPLAY 0.872340 (-2173 2350);
PAINT GREEN (-2173 2350);
DISPLAY INVISIBLE (-2173 2350);
FORCEADD OFFPAGE..2
R 2
(-3100 950);
FORCEPROP 2 LAST $XR0 26 
J 0
(-3324 950);
DISPLAY 0.638298 (-3324 950);
PAINT MONO (-3324 950);
FORCEPROP 2 LAST CDS_LIB standard
J 0
(-3100 950);
PAINT MONO (-3100 950);
DISPLAY INVISIBLE (-3100 950);
FORCEPROP 1 LAST OFFPAGE TRUE
J 2
(-3425 825);
DISPLAY 0.872340 (-3425 825);
DISPLAY INVISIBLE (-3425 825);
FORCEPROP 1 LAST COMMENT_BODY TRUE
J 2
(-3055 855);
DISPLAY 0.872340 (-3055 855);
PAINT GREEN (-3055 855);
DISPLAY INVISIBLE (-3055 855);
FORCEPROP 2 LAST PATH I3
J 0
(-3050 1025);
DISPLAY 1.021277 (-3050 1025);
DISPLAY INVISIBLE (-3050 1025);
FORCEADD TAP..1
R 2
(-2175 2450);
FORCEPROP 3 LASTPIN (-2125 2450) SIG_NAME M_G_CPU0_SB_CB<6>
J 0
(-2115 2460);
DISPLAY 0.659574 (-2115 2460);
PAINT MONO (-2115 2460);
DISPLAY INVISIBLE (-2115 2460);
FORCEPROP 1 LASTPIN (-2125 2450) BN 6
J 2
(-2113 2458);
DISPLAY 0.680851 (-2113 2458);
PAINT GREEN (-2113 2458);
FORCEPROP 2 LAST CDS_LIB standard
J 0
(-2175 2450);
DISPLAY INVISIBLE (-2175 2450);
FORCEPROP 1 LAST BODY_TYPE PLUMBING
J 2
(-2175 2500);
DISPLAY 0.872340 (-2175 2500);
PAINT GREEN (-2175 2500);
DISPLAY INVISIBLE (-2175 2500);
FORCEPROP 1 LAST HDL_TAP TRUE
J 2
(-2500 2325);
DISPLAY 0.872340 (-2500 2325);
DISPLAY INVISIBLE (-2500 2325);
FORCEPROP 1 LAST PATH I30
J 2
(-2173 2450);
DISPLAY 0.872340 (-2173 2450);
PAINT GREEN (-2173 2450);
DISPLAY INVISIBLE (-2173 2450);
FORCEADD TAP..1
R 2
(-2175 2400);
FORCEPROP 3 LASTPIN (-2125 2400) SIG_NAME M_G_CPU0_SB_CB<5>
J 0
(-2115 2410);
DISPLAY 0.659574 (-2115 2410);
PAINT MONO (-2115 2410);
DISPLAY INVISIBLE (-2115 2410);
FORCEPROP 1 LASTPIN (-2125 2400) BN 5
J 2
(-2113 2408);
DISPLAY 0.680851 (-2113 2408);
PAINT GREEN (-2113 2408);
FORCEPROP 2 LAST CDS_LIB standard
J 0
(-2175 2400);
DISPLAY INVISIBLE (-2175 2400);
FORCEPROP 1 LAST BODY_TYPE PLUMBING
J 2
(-2175 2450);
DISPLAY 0.872340 (-2175 2450);
PAINT GREEN (-2175 2450);
DISPLAY INVISIBLE (-2175 2450);
FORCEPROP 1 LAST HDL_TAP TRUE
J 2
(-2500 2275);
DISPLAY 0.872340 (-2500 2275);
DISPLAY INVISIBLE (-2500 2275);
FORCEPROP 1 LAST PATH I31
J 2
(-2173 2400);
DISPLAY 0.872340 (-2173 2400);
PAINT GREEN (-2173 2400);
DISPLAY INVISIBLE (-2173 2400);
FORCEADD TAP..1
R 2
(-2175 2500);
FORCEPROP 3 LASTPIN (-2125 2500) SIG_NAME M_G_CPU0_SB_CB<7>
J 0
(-2115 2510);
DISPLAY 0.659574 (-2115 2510);
PAINT MONO (-2115 2510);
DISPLAY INVISIBLE (-2115 2510);
FORCEPROP 1 LASTPIN (-2125 2500) BN 7
J 2
(-2113 2508);
DISPLAY 0.680851 (-2113 2508);
PAINT GREEN (-2113 2508);
FORCEPROP 2 LAST CDS_LIB standard
J 0
(-2175 2500);
DISPLAY INVISIBLE (-2175 2500);
FORCEPROP 1 LAST BODY_TYPE PLUMBING
J 2
(-2175 2550);
DISPLAY 0.872340 (-2175 2550);
PAINT GREEN (-2175 2550);
DISPLAY INVISIBLE (-2175 2550);
FORCEPROP 1 LAST HDL_TAP TRUE
J 2
(-2500 2375);
DISPLAY 0.872340 (-2500 2375);
DISPLAY INVISIBLE (-2500 2375);
FORCEPROP 1 LAST PATH I32
J 2
(-2173 2500);
DISPLAY 0.872340 (-2173 2500);
PAINT GREEN (-2173 2500);
DISPLAY INVISIBLE (-2173 2500);
FORCEADD TAP..1
R 2
(-2175 2600);
FORCEPROP 3 LASTPIN (-2125 2600) SIG_NAME M_G_CPU0_SA_CB<0>
J 0
(-2115 2610);
DISPLAY 0.659574 (-2115 2610);
PAINT MONO (-2115 2610);
DISPLAY INVISIBLE (-2115 2610);
FORCEPROP 1 LASTPIN (-2125 2600) BN 0
J 2
(-2113 2608);
DISPLAY 0.680851 (-2113 2608);
PAINT GREEN (-2113 2608);
FORCEPROP 2 LAST CDS_LIB standard
J 0
(-2175 2600);
PAINT MONO (-2175 2600);
DISPLAY INVISIBLE (-2175 2600);
FORCEPROP 1 LAST BODY_TYPE PLUMBING
J 2
(-2175 2650);
DISPLAY 0.872340 (-2175 2650);
PAINT GREEN (-2175 2650);
DISPLAY INVISIBLE (-2175 2650);
FORCEPROP 1 LAST HDL_TAP TRUE
J 2
(-2500 2475);
DISPLAY 0.872340 (-2500 2475);
DISPLAY INVISIBLE (-2500 2475);
FORCEPROP 1 LAST PATH I33
J 2
(-2173 2600);
DISPLAY 0.872340 (-2173 2600);
PAINT GREEN (-2173 2600);
DISPLAY INVISIBLE (-2173 2600);
FORCEADD TAP..1
R 2
(-2175 2650);
FORCEPROP 3 LASTPIN (-2125 2650) SIG_NAME M_G_CPU0_SA_CB<1>
J 0
(-2115 2660);
DISPLAY 0.659574 (-2115 2660);
PAINT MONO (-2115 2660);
DISPLAY INVISIBLE (-2115 2660);
FORCEPROP 1 LASTPIN (-2125 2650) BN 1
J 2
(-2113 2658);
DISPLAY 0.680851 (-2113 2658);
PAINT GREEN (-2113 2658);
FORCEPROP 2 LAST CDS_LIB standard
J 0
(-2175 2650);
DISPLAY INVISIBLE (-2175 2650);
FORCEPROP 1 LAST BODY_TYPE PLUMBING
J 2
(-2175 2700);
DISPLAY 0.872340 (-2175 2700);
PAINT GREEN (-2175 2700);
DISPLAY INVISIBLE (-2175 2700);
FORCEPROP 1 LAST HDL_TAP TRUE
J 2
(-2500 2525);
DISPLAY 0.872340 (-2500 2525);
DISPLAY INVISIBLE (-2500 2525);
FORCEPROP 1 LAST PATH I34
J 2
(-2173 2650);
DISPLAY 0.872340 (-2173 2650);
PAINT GREEN (-2173 2650);
DISPLAY INVISIBLE (-2173 2650);
FORCEADD TAP..1
R 2
(-2175 2700);
FORCEPROP 3 LASTPIN (-2125 2700) SIG_NAME M_G_CPU0_SA_CB<2>
J 0
(-2115 2710);
DISPLAY 0.659574 (-2115 2710);
PAINT MONO (-2115 2710);
DISPLAY INVISIBLE (-2115 2710);
FORCEPROP 1 LASTPIN (-2125 2700) BN 2
J 2
(-2113 2708);
DISPLAY 0.680851 (-2113 2708);
PAINT GREEN (-2113 2708);
FORCEPROP 2 LAST CDS_LIB standard
J 0
(-2175 2700);
DISPLAY INVISIBLE (-2175 2700);
FORCEPROP 1 LAST BODY_TYPE PLUMBING
J 2
(-2175 2750);
DISPLAY 0.872340 (-2175 2750);
PAINT GREEN (-2175 2750);
DISPLAY INVISIBLE (-2175 2750);
FORCEPROP 1 LAST HDL_TAP TRUE
J 2
(-2500 2575);
DISPLAY 0.872340 (-2500 2575);
DISPLAY INVISIBLE (-2500 2575);
FORCEPROP 1 LAST PATH I35
J 2
(-2173 2700);
DISPLAY 0.872340 (-2173 2700);
PAINT GREEN (-2173 2700);
DISPLAY INVISIBLE (-2173 2700);
FORCEADD TAP..1
R 2
(-2175 2750);
FORCEPROP 3 LASTPIN (-2125 2750) SIG_NAME M_G_CPU0_SA_CB<3>
J 0
(-2115 2760);
DISPLAY 0.659574 (-2115 2760);
PAINT MONO (-2115 2760);
DISPLAY INVISIBLE (-2115 2760);
FORCEPROP 1 LASTPIN (-2125 2750) BN 3
J 2
(-2113 2758);
DISPLAY 0.680851 (-2113 2758);
PAINT GREEN (-2113 2758);
FORCEPROP 2 LAST CDS_LIB standard
J 0
(-2175 2750);
DISPLAY INVISIBLE (-2175 2750);
FORCEPROP 1 LAST BODY_TYPE PLUMBING
J 2
(-2175 2800);
DISPLAY 0.872340 (-2175 2800);
PAINT GREEN (-2175 2800);
DISPLAY INVISIBLE (-2175 2800);
FORCEPROP 1 LAST HDL_TAP TRUE
J 2
(-2500 2625);
DISPLAY 0.872340 (-2500 2625);
DISPLAY INVISIBLE (-2500 2625);
FORCEPROP 1 LAST PATH I36
J 2
(-2173 2750);
DISPLAY 0.872340 (-2173 2750);
PAINT GREEN (-2173 2750);
DISPLAY INVISIBLE (-2173 2750);
FORCEADD TAP..1
R 2
(-2175 2850);
FORCEPROP 3 LASTPIN (-2125 2850) SIG_NAME M_G_CPU0_SA_CB<5>
J 0
(-2115 2860);
DISPLAY 0.659574 (-2115 2860);
PAINT MONO (-2115 2860);
DISPLAY INVISIBLE (-2115 2860);
FORCEPROP 1 LASTPIN (-2125 2850) BN 5
J 2
(-2113 2858);
DISPLAY 0.680851 (-2113 2858);
PAINT GREEN (-2113 2858);
FORCEPROP 2 LAST CDS_LIB standard
J 0
(-2175 2850);
DISPLAY INVISIBLE (-2175 2850);
FORCEPROP 1 LAST BODY_TYPE PLUMBING
J 2
(-2175 2900);
DISPLAY 0.872340 (-2175 2900);
PAINT GREEN (-2175 2900);
DISPLAY INVISIBLE (-2175 2900);
FORCEPROP 1 LAST HDL_TAP TRUE
J 2
(-2500 2725);
DISPLAY 0.872340 (-2500 2725);
DISPLAY INVISIBLE (-2500 2725);
FORCEPROP 1 LAST PATH I37
J 2
(-2173 2850);
DISPLAY 0.872340 (-2173 2850);
PAINT GREEN (-2173 2850);
DISPLAY INVISIBLE (-2173 2850);
FORCEADD TAP..1
R 2
(-2175 2800);
FORCEPROP 3 LASTPIN (-2125 2800) SIG_NAME M_G_CPU0_SA_CB<4>
J 0
(-2115 2810);
DISPLAY 0.659574 (-2115 2810);
PAINT MONO (-2115 2810);
DISPLAY INVISIBLE (-2115 2810);
FORCEPROP 1 LASTPIN (-2125 2800) BN 4
J 2
(-2113 2808);
DISPLAY 0.680851 (-2113 2808);
PAINT GREEN (-2113 2808);
FORCEPROP 2 LAST CDS_LIB standard
J 0
(-2175 2800);
DISPLAY INVISIBLE (-2175 2800);
FORCEPROP 1 LAST BODY_TYPE PLUMBING
J 2
(-2175 2850);
DISPLAY 0.872340 (-2175 2850);
PAINT GREEN (-2175 2850);
DISPLAY INVISIBLE (-2175 2850);
FORCEPROP 1 LAST HDL_TAP TRUE
J 2
(-2500 2675);
DISPLAY 0.872340 (-2500 2675);
DISPLAY INVISIBLE (-2500 2675);
FORCEPROP 1 LAST PATH I38
J 2
(-2173 2800);
DISPLAY 0.872340 (-2173 2800);
PAINT GREEN (-2173 2800);
DISPLAY INVISIBLE (-2173 2800);
FORCEADD TAP..1
R 2
(-2175 2950);
FORCEPROP 3 LASTPIN (-2125 2950) SIG_NAME M_G_CPU0_SA_CB<7>
J 0
(-2115 2960);
DISPLAY 0.659574 (-2115 2960);
PAINT MONO (-2115 2960);
DISPLAY INVISIBLE (-2115 2960);
FORCEPROP 1 LASTPIN (-2125 2950) BN 7
J 2
(-2113 2958);
DISPLAY 0.680851 (-2113 2958);
PAINT GREEN (-2113 2958);
FORCEPROP 2 LAST CDS_LIB standard
J 0
(-2175 2950);
DISPLAY INVISIBLE (-2175 2950);
FORCEPROP 1 LAST BODY_TYPE PLUMBING
J 2
(-2175 3000);
DISPLAY 0.872340 (-2175 3000);
PAINT GREEN (-2175 3000);
DISPLAY INVISIBLE (-2175 3000);
FORCEPROP 1 LAST HDL_TAP TRUE
J 2
(-2500 2825);
DISPLAY 0.872340 (-2500 2825);
DISPLAY INVISIBLE (-2500 2825);
FORCEPROP 1 LAST PATH I39
J 2
(-2173 2950);
DISPLAY 0.872340 (-2173 2950);
PAINT GREEN (-2173 2950);
DISPLAY INVISIBLE (-2173 2950);
FORCEADD OFFPAGE..3
R 2
(-3100 1500);
FORCEPROP 2 LAST $XR0 114 
J 0
(-3380 1500);
DISPLAY 0.638298 (-3380 1500);
PAINT MONO (-3380 1500);
FORCEPROP 2 LAST CDS_LIB standard
J 0
(-3100 1500);
PAINT MONO (-3100 1500);
DISPLAY INVISIBLE (-3100 1500);
FORCEPROP 1 LAST OFFPAGE TRUE
J 2
(-3425 1375);
DISPLAY 0.872340 (-3425 1375);
DISPLAY INVISIBLE (-3425 1375);
FORCEPROP 1 LAST COMMENT_BODY TRUE
J 2
(-3050 1400);
DISPLAY 0.872340 (-3050 1400);
PAINT GREEN (-3050 1400);
DISPLAY INVISIBLE (-3050 1400);
FORCEPROP 2 LAST PATH I4
J 0
(-3050 1575);
DISPLAY 1.021277 (-3050 1575);
DISPLAY INVISIBLE (-3050 1575);
FORCEADD TAP..1
R 2
(-2175 2900);
FORCEPROP 3 LASTPIN (-2125 2900) SIG_NAME M_G_CPU0_SA_CB<6>
J 0
(-2115 2910);
DISPLAY 0.659574 (-2115 2910);
PAINT MONO (-2115 2910);
DISPLAY INVISIBLE (-2115 2910);
FORCEPROP 1 LASTPIN (-2125 2900) BN 6
J 2
(-2113 2908);
DISPLAY 0.680851 (-2113 2908);
PAINT GREEN (-2113 2908);
FORCEPROP 2 LAST CDS_LIB standard
J 0
(-2175 2900);
DISPLAY INVISIBLE (-2175 2900);
FORCEPROP 1 LAST BODY_TYPE PLUMBING
J 2
(-2175 2950);
DISPLAY 0.872340 (-2175 2950);
PAINT GREEN (-2175 2950);
DISPLAY INVISIBLE (-2175 2950);
FORCEPROP 1 LAST HDL_TAP TRUE
J 2
(-2500 2775);
DISPLAY 0.872340 (-2500 2775);
DISPLAY INVISIBLE (-2500 2775);
FORCEPROP 1 LAST PATH I40
J 2
(-2173 2900);
DISPLAY 0.872340 (-2173 2900);
PAINT GREEN (-2173 2900);
DISPLAY INVISIBLE (-2173 2900);
FORCEADD TAP..1
R 2
(-2175 3650);
FORCEPROP 3 LASTPIN (-2125 3650) SIG_NAME M_G_CPU0_SB_CA<0>
J 0
(-2115 3660);
DISPLAY 0.659574 (-2115 3660);
PAINT MONO (-2115 3660);
DISPLAY INVISIBLE (-2115 3660);
FORCEPROP 1 LASTPIN (-2125 3650) BN 0
J 2
(-2113 3658);
DISPLAY 0.680851 (-2113 3658);
PAINT GREEN (-2113 3658);
FORCEPROP 2 LAST CDS_LIB standard
J 0
(-2175 3650);
DISPLAY INVISIBLE (-2175 3650);
FORCEPROP 1 LAST BODY_TYPE PLUMBING
J 2
(-2175 3700);
DISPLAY 0.872340 (-2175 3700);
PAINT GREEN (-2175 3700);
DISPLAY INVISIBLE (-2175 3700);
FORCEPROP 1 LAST HDL_TAP TRUE
J 2
(-2500 3525);
DISPLAY 0.872340 (-2500 3525);
DISPLAY INVISIBLE (-2500 3525);
FORCEPROP 1 LAST PATH I41
J 2
(-2173 3650);
DISPLAY 0.872340 (-2173 3650);
PAINT GREEN (-2173 3650);
DISPLAY INVISIBLE (-2173 3650);
FORCEADD TAP..1
R 2
(-2175 3700);
FORCEPROP 3 LASTPIN (-2125 3700) SIG_NAME M_G_CPU0_SB_CA<1>
J 0
(-2115 3710);
DISPLAY 0.659574 (-2115 3710);
PAINT MONO (-2115 3710);
DISPLAY INVISIBLE (-2115 3710);
FORCEPROP 1 LASTPIN (-2125 3700) BN 1
J 2
(-2113 3708);
DISPLAY 0.680851 (-2113 3708);
PAINT GREEN (-2113 3708);
FORCEPROP 2 LAST CDS_LIB standard
J 0
(-2175 3700);
DISPLAY INVISIBLE (-2175 3700);
FORCEPROP 1 LAST BODY_TYPE PLUMBING
J 2
(-2175 3750);
DISPLAY 0.872340 (-2175 3750);
PAINT GREEN (-2175 3750);
DISPLAY INVISIBLE (-2175 3750);
FORCEPROP 1 LAST HDL_TAP TRUE
J 2
(-2500 3575);
DISPLAY 0.872340 (-2500 3575);
DISPLAY INVISIBLE (-2500 3575);
FORCEPROP 1 LAST PATH I42
J 2
(-2173 3700);
DISPLAY 0.872340 (-2173 3700);
PAINT GREEN (-2173 3700);
DISPLAY INVISIBLE (-2173 3700);
FORCEADD TAP..1
R 2
(-2175 3750);
FORCEPROP 3 LASTPIN (-2125 3750) SIG_NAME M_G_CPU0_SB_CA<2>
J 0
(-2115 3760);
DISPLAY 0.659574 (-2115 3760);
PAINT MONO (-2115 3760);
DISPLAY INVISIBLE (-2115 3760);
FORCEPROP 1 LASTPIN (-2125 3750) BN 2
J 2
(-2113 3758);
DISPLAY 0.680851 (-2113 3758);
PAINT GREEN (-2113 3758);
FORCEPROP 2 LAST CDS_LIB standard
J 0
(-2175 3750);
DISPLAY INVISIBLE (-2175 3750);
FORCEPROP 1 LAST BODY_TYPE PLUMBING
J 2
(-2175 3800);
DISPLAY 0.872340 (-2175 3800);
PAINT GREEN (-2175 3800);
DISPLAY INVISIBLE (-2175 3800);
FORCEPROP 1 LAST HDL_TAP TRUE
J 2
(-2500 3625);
DISPLAY 0.872340 (-2500 3625);
DISPLAY INVISIBLE (-2500 3625);
FORCEPROP 1 LAST PATH I43
J 2
(-2173 3750);
DISPLAY 0.872340 (-2173 3750);
PAINT GREEN (-2173 3750);
DISPLAY INVISIBLE (-2173 3750);
FORCEADD TAP..1
R 2
(-2175 3800);
FORCEPROP 3 LASTPIN (-2125 3800) SIG_NAME M_G_CPU0_SB_CA<3>
J 0
(-2115 3810);
DISPLAY 0.659574 (-2115 3810);
PAINT MONO (-2115 3810);
DISPLAY INVISIBLE (-2115 3810);
FORCEPROP 1 LASTPIN (-2125 3800) BN 3
J 2
(-2113 3808);
DISPLAY 0.680851 (-2113 3808);
PAINT GREEN (-2113 3808);
FORCEPROP 2 LAST CDS_LIB standard
J 0
(-2175 3800);
DISPLAY INVISIBLE (-2175 3800);
FORCEPROP 1 LAST BODY_TYPE PLUMBING
J 2
(-2175 3850);
DISPLAY 0.872340 (-2175 3850);
PAINT GREEN (-2175 3850);
DISPLAY INVISIBLE (-2175 3850);
FORCEPROP 1 LAST HDL_TAP TRUE
J 2
(-2500 3675);
DISPLAY 0.872340 (-2500 3675);
DISPLAY INVISIBLE (-2500 3675);
FORCEPROP 1 LAST PATH I44
J 2
(-2173 3800);
DISPLAY 0.872340 (-2173 3800);
PAINT GREEN (-2173 3800);
DISPLAY INVISIBLE (-2173 3800);
FORCEADD TAP..1
R 2
(-2175 3850);
FORCEPROP 3 LASTPIN (-2125 3850) SIG_NAME M_G_CPU0_SB_CA<4>
J 0
(-2115 3860);
DISPLAY 0.659574 (-2115 3860);
PAINT MONO (-2115 3860);
DISPLAY INVISIBLE (-2115 3860);
FORCEPROP 1 LASTPIN (-2125 3850) BN 4
J 2
(-2113 3858);
DISPLAY 0.680851 (-2113 3858);
PAINT GREEN (-2113 3858);
FORCEPROP 2 LAST CDS_LIB standard
J 0
(-2175 3850);
DISPLAY INVISIBLE (-2175 3850);
FORCEPROP 1 LAST BODY_TYPE PLUMBING
J 2
(-2175 3900);
DISPLAY 0.872340 (-2175 3900);
PAINT GREEN (-2175 3900);
DISPLAY INVISIBLE (-2175 3900);
FORCEPROP 1 LAST HDL_TAP TRUE
J 2
(-2500 3725);
DISPLAY 0.872340 (-2500 3725);
DISPLAY INVISIBLE (-2500 3725);
FORCEPROP 1 LAST PATH I45
J 2
(-2173 3850);
DISPLAY 0.872340 (-2173 3850);
PAINT GREEN (-2173 3850);
DISPLAY INVISIBLE (-2173 3850);
FORCEADD TAP..1
R 2
(-2175 3900);
FORCEPROP 3 LASTPIN (-2125 3900) SIG_NAME M_G_CPU0_SB_CA<5>
J 0
(-2115 3910);
DISPLAY 0.659574 (-2115 3910);
PAINT MONO (-2115 3910);
DISPLAY INVISIBLE (-2115 3910);
FORCEPROP 1 LASTPIN (-2125 3900) BN 5
J 2
(-2113 3908);
DISPLAY 0.680851 (-2113 3908);
PAINT GREEN (-2113 3908);
FORCEPROP 2 LAST CDS_LIB standard
J 0
(-2175 3900);
DISPLAY INVISIBLE (-2175 3900);
FORCEPROP 1 LAST BODY_TYPE PLUMBING
J 2
(-2175 3950);
DISPLAY 0.872340 (-2175 3950);
PAINT GREEN (-2175 3950);
DISPLAY INVISIBLE (-2175 3950);
FORCEPROP 1 LAST HDL_TAP TRUE
J 2
(-2500 3775);
DISPLAY 0.872340 (-2500 3775);
DISPLAY INVISIBLE (-2500 3775);
FORCEPROP 1 LAST PATH I46
J 2
(-2173 3900);
DISPLAY 0.872340 (-2173 3900);
PAINT GREEN (-2173 3900);
DISPLAY INVISIBLE (-2173 3900);
FORCEADD TAP..1
R 2
(-2175 3950);
FORCEPROP 3 LASTPIN (-2125 3950) SIG_NAME M_G_CPU0_SB_CA<6>
J 0
(-2115 3960);
DISPLAY 0.659574 (-2115 3960);
PAINT MONO (-2115 3960);
DISPLAY INVISIBLE (-2115 3960);
FORCEPROP 1 LASTPIN (-2125 3950) BN 6
J 2
(-2113 3958);
DISPLAY 0.680851 (-2113 3958);
PAINT GREEN (-2113 3958);
FORCEPROP 2 LAST CDS_LIB standard
J 0
(-2175 3950);
DISPLAY INVISIBLE (-2175 3950);
FORCEPROP 1 LAST BODY_TYPE PLUMBING
J 2
(-2175 4000);
DISPLAY 0.872340 (-2175 4000);
PAINT GREEN (-2175 4000);
DISPLAY INVISIBLE (-2175 4000);
FORCEPROP 1 LAST HDL_TAP TRUE
J 2
(-2500 3825);
DISPLAY 0.872340 (-2500 3825);
DISPLAY INVISIBLE (-2500 3825);
FORCEPROP 1 LAST PATH I47
J 2
(-2173 3950);
DISPLAY 0.872340 (-2173 3950);
PAINT GREEN (-2173 3950);
DISPLAY INVISIBLE (-2173 3950);
FORCEADD TAP..1
(-525 1200);
FORCEPROP 3 LASTPIN (-575 1200) SIG_NAME M_G_CPU0_SB_DQ<1>
J 0
(-565 1210);
DISPLAY 0.659574 (-565 1210);
PAINT MONO (-565 1210);
DISPLAY INVISIBLE (-565 1210);
FORCEPROP 1 LASTPIN (-575 1200) BN 1
J 0
(-587 1208);
DISPLAY 0.680851 (-587 1208);
PAINT GREEN (-587 1208);
FORCEPROP 2 LAST CDS_LIB standard
J 0
(-525 1200);
PAINT MONO (-525 1200);
DISPLAY INVISIBLE (-525 1200);
FORCEPROP 1 LAST BODY_TYPE PLUMBING
J 0
(-525 1250);
DISPLAY 0.872340 (-525 1250);
PAINT GREEN (-525 1250);
DISPLAY INVISIBLE (-525 1250);
FORCEPROP 1 LAST HDL_TAP TRUE
J 0
(-200 1075);
DISPLAY 0.872340 (-200 1075);
DISPLAY INVISIBLE (-200 1075);
FORCEPROP 1 LAST PATH I48
J 0
(-527 1200);
DISPLAY 0.872340 (-527 1200);
PAINT GREEN (-527 1200);
DISPLAY INVISIBLE (-527 1200);
FORCEADD TAP..1
(-525 1150);
FORCEPROP 3 LASTPIN (-575 1150) SIG_NAME M_G_CPU0_SB_DQ<0>
J 0
(-565 1160);
DISPLAY 0.659574 (-565 1160);
PAINT MONO (-565 1160);
DISPLAY INVISIBLE (-565 1160);
FORCEPROP 1 LASTPIN (-575 1150) BN 0
J 0
(-587 1158);
DISPLAY 0.680851 (-587 1158);
PAINT GREEN (-587 1158);
FORCEPROP 2 LAST CDS_LIB standard
J 0
(-525 1150);
PAINT MONO (-525 1150);
DISPLAY INVISIBLE (-525 1150);
FORCEPROP 1 LAST BODY_TYPE PLUMBING
J 0
(-525 1200);
DISPLAY 0.872340 (-525 1200);
PAINT GREEN (-525 1200);
DISPLAY INVISIBLE (-525 1200);
FORCEPROP 1 LAST HDL_TAP TRUE
J 0
(-200 1025);
DISPLAY 0.872340 (-200 1025);
DISPLAY INVISIBLE (-200 1025);
FORCEPROP 1 LAST PATH I49
J 0
(-527 1150);
DISPLAY 0.872340 (-527 1150);
PAINT GREEN (-527 1150);
DISPLAY INVISIBLE (-527 1150);
FORCEADD TAP..1
(-525 1250);
FORCEPROP 3 LASTPIN (-575 1250) SIG_NAME M_G_CPU0_SB_DQ<2>
J 0
(-565 1260);
DISPLAY 0.659574 (-565 1260);
PAINT MONO (-565 1260);
DISPLAY INVISIBLE (-565 1260);
FORCEPROP 1 LASTPIN (-575 1250) BN 2
J 0
(-587 1258);
DISPLAY 0.680851 (-587 1258);
PAINT GREEN (-587 1258);
FORCEPROP 2 LAST CDS_LIB standard
J 0
(-525 1250);
PAINT MONO (-525 1250);
DISPLAY INVISIBLE (-525 1250);
FORCEPROP 1 LAST BODY_TYPE PLUMBING
J 0
(-525 1300);
DISPLAY 0.872340 (-525 1300);
PAINT GREEN (-525 1300);
DISPLAY INVISIBLE (-525 1300);
FORCEPROP 1 LAST HDL_TAP TRUE
J 0
(-200 1125);
DISPLAY 0.872340 (-200 1125);
DISPLAY INVISIBLE (-200 1125);
FORCEPROP 1 LAST PATH I50
J 0
(-527 1250);
DISPLAY 0.872340 (-527 1250);
PAINT GREEN (-527 1250);
DISPLAY INVISIBLE (-527 1250);
FORCEADD TAP..1
(-525 1350);
FORCEPROP 3 LASTPIN (-575 1350) SIG_NAME M_G_CPU0_SB_DQ<4>
J 0
(-565 1360);
DISPLAY 0.659574 (-565 1360);
PAINT MONO (-565 1360);
DISPLAY INVISIBLE (-565 1360);
FORCEPROP 1 LASTPIN (-575 1350) BN 4
J 0
(-587 1358);
DISPLAY 0.680851 (-587 1358);
PAINT GREEN (-587 1358);
FORCEPROP 2 LAST CDS_LIB standard
J 0
(-525 1350);
PAINT MONO (-525 1350);
DISPLAY INVISIBLE (-525 1350);
FORCEPROP 1 LAST BODY_TYPE PLUMBING
J 0
(-525 1400);
DISPLAY 0.872340 (-525 1400);
PAINT GREEN (-525 1400);
DISPLAY INVISIBLE (-525 1400);
FORCEPROP 1 LAST HDL_TAP TRUE
J 0
(-200 1225);
DISPLAY 0.872340 (-200 1225);
DISPLAY INVISIBLE (-200 1225);
FORCEPROP 1 LAST PATH I51
J 0
(-527 1350);
DISPLAY 0.872340 (-527 1350);
PAINT GREEN (-527 1350);
DISPLAY INVISIBLE (-527 1350);
FORCEADD TAP..1
(-525 1300);
FORCEPROP 3 LASTPIN (-575 1300) SIG_NAME M_G_CPU0_SB_DQ<3>
J 0
(-565 1310);
DISPLAY 0.659574 (-565 1310);
PAINT MONO (-565 1310);
DISPLAY INVISIBLE (-565 1310);
FORCEPROP 1 LASTPIN (-575 1300) BN 3
J 0
(-587 1308);
DISPLAY 0.680851 (-587 1308);
PAINT GREEN (-587 1308);
FORCEPROP 2 LAST CDS_LIB standard
J 0
(-525 1300);
PAINT MONO (-525 1300);
DISPLAY INVISIBLE (-525 1300);
FORCEPROP 1 LAST BODY_TYPE PLUMBING
J 0
(-525 1350);
DISPLAY 0.872340 (-525 1350);
PAINT GREEN (-525 1350);
DISPLAY INVISIBLE (-525 1350);
FORCEPROP 1 LAST HDL_TAP TRUE
J 0
(-200 1175);
DISPLAY 0.872340 (-200 1175);
DISPLAY INVISIBLE (-200 1175);
FORCEPROP 1 LAST PATH I52
J 0
(-527 1300);
DISPLAY 0.872340 (-527 1300);
PAINT GREEN (-527 1300);
DISPLAY INVISIBLE (-527 1300);
FORCEADD TAP..1
(-525 1450);
FORCEPROP 3 LASTPIN (-575 1450) SIG_NAME M_G_CPU0_SB_DQ<6>
J 0
(-565 1460);
DISPLAY 0.659574 (-565 1460);
PAINT MONO (-565 1460);
DISPLAY INVISIBLE (-565 1460);
FORCEPROP 1 LASTPIN (-575 1450) BN 6
J 0
(-587 1458);
DISPLAY 0.680851 (-587 1458);
PAINT GREEN (-587 1458);
FORCEPROP 2 LAST CDS_LIB standard
J 0
(-525 1450);
PAINT MONO (-525 1450);
DISPLAY INVISIBLE (-525 1450);
FORCEPROP 1 LAST BODY_TYPE PLUMBING
J 0
(-525 1500);
DISPLAY 0.872340 (-525 1500);
PAINT GREEN (-525 1500);
DISPLAY INVISIBLE (-525 1500);
FORCEPROP 1 LAST HDL_TAP TRUE
J 0
(-200 1325);
DISPLAY 0.872340 (-200 1325);
DISPLAY INVISIBLE (-200 1325);
FORCEPROP 1 LAST PATH I53
J 0
(-527 1450);
DISPLAY 0.872340 (-527 1450);
PAINT GREEN (-527 1450);
DISPLAY INVISIBLE (-527 1450);
FORCEADD TAP..1
(-525 1400);
FORCEPROP 3 LASTPIN (-575 1400) SIG_NAME M_G_CPU0_SB_DQ<5>
J 0
(-565 1410);
DISPLAY 0.659574 (-565 1410);
PAINT MONO (-565 1410);
DISPLAY INVISIBLE (-565 1410);
FORCEPROP 1 LASTPIN (-575 1400) BN 5
J 0
(-587 1408);
DISPLAY 0.680851 (-587 1408);
PAINT GREEN (-587 1408);
FORCEPROP 2 LAST CDS_LIB standard
J 0
(-525 1400);
PAINT MONO (-525 1400);
DISPLAY INVISIBLE (-525 1400);
FORCEPROP 1 LAST BODY_TYPE PLUMBING
J 0
(-525 1450);
DISPLAY 0.872340 (-525 1450);
PAINT GREEN (-525 1450);
DISPLAY INVISIBLE (-525 1450);
FORCEPROP 1 LAST HDL_TAP TRUE
J 0
(-200 1275);
DISPLAY 0.872340 (-200 1275);
DISPLAY INVISIBLE (-200 1275);
FORCEPROP 1 LAST PATH I54
J 0
(-527 1400);
DISPLAY 0.872340 (-527 1400);
PAINT GREEN (-527 1400);
DISPLAY INVISIBLE (-527 1400);
FORCEADD TAP..1
(-525 1500);
FORCEPROP 3 LASTPIN (-575 1500) SIG_NAME M_G_CPU0_SB_DQ<7>
J 0
(-565 1510);
DISPLAY 0.659574 (-565 1510);
PAINT MONO (-565 1510);
DISPLAY INVISIBLE (-565 1510);
FORCEPROP 1 LASTPIN (-575 1500) BN 7
J 0
(-587 1508);
DISPLAY 0.680851 (-587 1508);
PAINT GREEN (-587 1508);
FORCEPROP 2 LAST CDS_LIB standard
J 0
(-525 1500);
PAINT MONO (-525 1500);
DISPLAY INVISIBLE (-525 1500);
FORCEPROP 1 LAST BODY_TYPE PLUMBING
J 0
(-525 1550);
DISPLAY 0.872340 (-525 1550);
PAINT GREEN (-525 1550);
DISPLAY INVISIBLE (-525 1550);
FORCEPROP 1 LAST HDL_TAP TRUE
J 0
(-200 1375);
DISPLAY 0.872340 (-200 1375);
DISPLAY INVISIBLE (-200 1375);
FORCEPROP 1 LAST PATH I55
J 0
(-527 1500);
DISPLAY 0.872340 (-527 1500);
PAINT GREEN (-527 1500);
DISPLAY INVISIBLE (-527 1500);
FORCEADD TAP..1
(-525 1550);
FORCEPROP 3 LASTPIN (-575 1550) SIG_NAME M_G_CPU0_SB_DQ<8>
J 0
(-565 1560);
DISPLAY 0.659574 (-565 1560);
PAINT MONO (-565 1560);
DISPLAY INVISIBLE (-565 1560);
FORCEPROP 1 LASTPIN (-575 1550) BN 8
J 0
(-587 1558);
DISPLAY 0.680851 (-587 1558);
PAINT GREEN (-587 1558);
FORCEPROP 2 LAST CDS_LIB standard
J 0
(-525 1550);
PAINT MONO (-525 1550);
DISPLAY INVISIBLE (-525 1550);
FORCEPROP 1 LAST BODY_TYPE PLUMBING
J 0
(-525 1600);
DISPLAY 0.872340 (-525 1600);
PAINT GREEN (-525 1600);
DISPLAY INVISIBLE (-525 1600);
FORCEPROP 1 LAST HDL_TAP TRUE
J 0
(-200 1425);
DISPLAY 0.872340 (-200 1425);
DISPLAY INVISIBLE (-200 1425);
FORCEPROP 1 LAST PATH I56
J 0
(-527 1550);
DISPLAY 0.872340 (-527 1550);
PAINT GREEN (-527 1550);
DISPLAY INVISIBLE (-527 1550);
FORCEADD TAP..1
(-525 1600);
FORCEPROP 3 LASTPIN (-575 1600) SIG_NAME M_G_CPU0_SB_DQ<9>
J 0
(-565 1610);
DISPLAY 0.659574 (-565 1610);
PAINT MONO (-565 1610);
DISPLAY INVISIBLE (-565 1610);
FORCEPROP 1 LASTPIN (-575 1600) BN 9
J 0
(-587 1608);
DISPLAY 0.680851 (-587 1608);
PAINT GREEN (-587 1608);
FORCEPROP 2 LAST CDS_LIB standard
J 0
(-525 1600);
PAINT MONO (-525 1600);
DISPLAY INVISIBLE (-525 1600);
FORCEPROP 1 LAST BODY_TYPE PLUMBING
J 0
(-525 1650);
DISPLAY 0.872340 (-525 1650);
PAINT GREEN (-525 1650);
DISPLAY INVISIBLE (-525 1650);
FORCEPROP 1 LAST HDL_TAP TRUE
J 0
(-200 1475);
DISPLAY 0.872340 (-200 1475);
DISPLAY INVISIBLE (-200 1475);
FORCEPROP 1 LAST PATH I57
J 0
(-527 1600);
DISPLAY 0.872340 (-527 1600);
PAINT GREEN (-527 1600);
DISPLAY INVISIBLE (-527 1600);
FORCEADD TAP..1
(-525 1700);
FORCEPROP 3 LASTPIN (-575 1700) SIG_NAME M_G_CPU0_SB_DQ<11>
J 0
(-565 1710);
DISPLAY 0.659574 (-565 1710);
PAINT MONO (-565 1710);
DISPLAY INVISIBLE (-565 1710);
FORCEPROP 1 LASTPIN (-575 1700) BN 11
J 0
(-587 1708);
DISPLAY 0.680851 (-587 1708);
PAINT GREEN (-587 1708);
FORCEPROP 2 LAST CDS_LIB standard
J 0
(-525 1700);
PAINT MONO (-525 1700);
DISPLAY INVISIBLE (-525 1700);
FORCEPROP 1 LAST BODY_TYPE PLUMBING
J 0
(-525 1750);
DISPLAY 0.872340 (-525 1750);
PAINT GREEN (-525 1750);
DISPLAY INVISIBLE (-525 1750);
FORCEPROP 1 LAST HDL_TAP TRUE
J 0
(-200 1575);
DISPLAY 0.872340 (-200 1575);
DISPLAY INVISIBLE (-200 1575);
FORCEPROP 1 LAST PATH I58
J 0
(-527 1700);
DISPLAY 0.872340 (-527 1700);
PAINT GREEN (-527 1700);
DISPLAY INVISIBLE (-527 1700);
FORCEADD TAP..1
(-525 1650);
FORCEPROP 3 LASTPIN (-575 1650) SIG_NAME M_G_CPU0_SB_DQ<10>
J 0
(-565 1660);
DISPLAY 0.659574 (-565 1660);
PAINT MONO (-565 1660);
DISPLAY INVISIBLE (-565 1660);
FORCEPROP 1 LASTPIN (-575 1650) BN 10
J 0
(-587 1658);
DISPLAY 0.680851 (-587 1658);
PAINT GREEN (-587 1658);
FORCEPROP 2 LAST CDS_LIB standard
J 0
(-525 1650);
PAINT MONO (-525 1650);
DISPLAY INVISIBLE (-525 1650);
FORCEPROP 1 LAST BODY_TYPE PLUMBING
J 0
(-525 1700);
DISPLAY 0.872340 (-525 1700);
PAINT GREEN (-525 1700);
DISPLAY INVISIBLE (-525 1700);
FORCEPROP 1 LAST HDL_TAP TRUE
J 0
(-200 1525);
DISPLAY 0.872340 (-200 1525);
DISPLAY INVISIBLE (-200 1525);
FORCEPROP 1 LAST PATH I59
J 0
(-527 1650);
DISPLAY 0.872340 (-527 1650);
PAINT GREEN (-527 1650);
DISPLAY INVISIBLE (-527 1650);
FORCEADD OFFPAGE..1
(-3000 1850);
FORCEPROP 2 LAST $XR0 94 
J 0
(-3251 1850);
DISPLAY 0.638298 (-3251 1850);
PAINT MONO (-3251 1850);
FORCEPROP 2 LAST CDS_LIB standard
J 0
(-3000 1850);
PAINT MONO (-3000 1850);
DISPLAY INVISIBLE (-3000 1850);
FORCEPROP 1 LAST OFFPAGE TRUE
J 0
(-2675 1725);
DISPLAY 0.872340 (-2675 1725);
DISPLAY INVISIBLE (-2675 1725);
FORCEPROP 1 LAST COMMENT_BODY TRUE
J 0
(-2875 1750);
DISPLAY 0.872340 (-2875 1750);
PAINT GREEN (-2875 1750);
DISPLAY INVISIBLE (-2875 1750);
FORCEPROP 2 LAST PATH I6
J 0
(-2950 1925);
DISPLAY 1.021277 (-2950 1925);
DISPLAY INVISIBLE (-2950 1925);
FORCEADD TAP..1
(-525 1750);
FORCEPROP 3 LASTPIN (-575 1750) SIG_NAME M_G_CPU0_SB_DQ<12>
J 0
(-565 1760);
DISPLAY 0.659574 (-565 1760);
PAINT MONO (-565 1760);
DISPLAY INVISIBLE (-565 1760);
FORCEPROP 1 LASTPIN (-575 1750) BN 12
J 0
(-587 1758);
DISPLAY 0.680851 (-587 1758);
PAINT GREEN (-587 1758);
FORCEPROP 2 LAST CDS_LIB standard
J 0
(-525 1750);
PAINT MONO (-525 1750);
DISPLAY INVISIBLE (-525 1750);
FORCEPROP 1 LAST BODY_TYPE PLUMBING
J 0
(-525 1800);
DISPLAY 0.872340 (-525 1800);
PAINT GREEN (-525 1800);
DISPLAY INVISIBLE (-525 1800);
FORCEPROP 1 LAST HDL_TAP TRUE
J 0
(-200 1625);
DISPLAY 0.872340 (-200 1625);
DISPLAY INVISIBLE (-200 1625);
FORCEPROP 1 LAST PATH I60
J 0
(-527 1750);
DISPLAY 0.872340 (-527 1750);
PAINT GREEN (-527 1750);
DISPLAY INVISIBLE (-527 1750);
FORCEADD TAP..1
(-525 1800);
FORCEPROP 3 LASTPIN (-575 1800) SIG_NAME M_G_CPU0_SB_DQ<13>
J 0
(-565 1810);
DISPLAY 0.659574 (-565 1810);
PAINT MONO (-565 1810);
DISPLAY INVISIBLE (-565 1810);
FORCEPROP 1 LASTPIN (-575 1800) BN 13
J 0
(-587 1808);
DISPLAY 0.680851 (-587 1808);
PAINT GREEN (-587 1808);
FORCEPROP 2 LAST CDS_LIB standard
J 0
(-525 1800);
PAINT MONO (-525 1800);
DISPLAY INVISIBLE (-525 1800);
FORCEPROP 1 LAST BODY_TYPE PLUMBING
J 0
(-525 1850);
DISPLAY 0.872340 (-525 1850);
PAINT GREEN (-525 1850);
DISPLAY INVISIBLE (-525 1850);
FORCEPROP 1 LAST HDL_TAP TRUE
J 0
(-200 1675);
DISPLAY 0.872340 (-200 1675);
DISPLAY INVISIBLE (-200 1675);
FORCEPROP 1 LAST PATH I61
J 0
(-527 1800);
DISPLAY 0.872340 (-527 1800);
PAINT GREEN (-527 1800);
DISPLAY INVISIBLE (-527 1800);
FORCEADD TAP..1
(-525 1850);
FORCEPROP 3 LASTPIN (-575 1850) SIG_NAME M_G_CPU0_SB_DQ<14>
J 0
(-565 1860);
DISPLAY 0.659574 (-565 1860);
PAINT MONO (-565 1860);
DISPLAY INVISIBLE (-565 1860);
FORCEPROP 1 LASTPIN (-575 1850) BN 14
J 0
(-587 1858);
DISPLAY 0.680851 (-587 1858);
PAINT GREEN (-587 1858);
FORCEPROP 2 LAST CDS_LIB standard
J 0
(-525 1850);
PAINT MONO (-525 1850);
DISPLAY INVISIBLE (-525 1850);
FORCEPROP 1 LAST BODY_TYPE PLUMBING
J 0
(-525 1900);
DISPLAY 0.872340 (-525 1900);
PAINT GREEN (-525 1900);
DISPLAY INVISIBLE (-525 1900);
FORCEPROP 1 LAST HDL_TAP TRUE
J 0
(-200 1725);
DISPLAY 0.872340 (-200 1725);
DISPLAY INVISIBLE (-200 1725);
FORCEPROP 1 LAST PATH I62
J 0
(-527 1850);
DISPLAY 0.872340 (-527 1850);
PAINT GREEN (-527 1850);
DISPLAY INVISIBLE (-527 1850);
FORCEADD TAP..1
(-525 1950);
FORCEPROP 3 LASTPIN (-575 1950) SIG_NAME M_G_CPU0_SB_DQ<16>
J 0
(-565 1960);
DISPLAY 0.659574 (-565 1960);
PAINT MONO (-565 1960);
DISPLAY INVISIBLE (-565 1960);
FORCEPROP 1 LASTPIN (-575 1950) BN 16
J 0
(-587 1958);
DISPLAY 0.680851 (-587 1958);
PAINT GREEN (-587 1958);
FORCEPROP 2 LAST CDS_LIB standard
J 0
(-525 1950);
PAINT MONO (-525 1950);
DISPLAY INVISIBLE (-525 1950);
FORCEPROP 1 LAST BODY_TYPE PLUMBING
J 0
(-525 2000);
DISPLAY 0.872340 (-525 2000);
PAINT GREEN (-525 2000);
DISPLAY INVISIBLE (-525 2000);
FORCEPROP 1 LAST HDL_TAP TRUE
J 0
(-200 1825);
DISPLAY 0.872340 (-200 1825);
DISPLAY INVISIBLE (-200 1825);
FORCEPROP 1 LAST PATH I63
J 0
(-527 1950);
DISPLAY 0.872340 (-527 1950);
PAINT GREEN (-527 1950);
DISPLAY INVISIBLE (-527 1950);
FORCEADD TAP..1
(-525 1900);
FORCEPROP 3 LASTPIN (-575 1900) SIG_NAME M_G_CPU0_SB_DQ<15>
J 0
(-565 1910);
DISPLAY 0.659574 (-565 1910);
PAINT MONO (-565 1910);
DISPLAY INVISIBLE (-565 1910);
FORCEPROP 1 LASTPIN (-575 1900) BN 15
J 0
(-587 1908);
DISPLAY 0.680851 (-587 1908);
PAINT GREEN (-587 1908);
FORCEPROP 2 LAST CDS_LIB standard
J 0
(-525 1900);
PAINT MONO (-525 1900);
DISPLAY INVISIBLE (-525 1900);
FORCEPROP 1 LAST BODY_TYPE PLUMBING
J 0
(-525 1950);
DISPLAY 0.872340 (-525 1950);
PAINT GREEN (-525 1950);
DISPLAY INVISIBLE (-525 1950);
FORCEPROP 1 LAST HDL_TAP TRUE
J 0
(-200 1775);
DISPLAY 0.872340 (-200 1775);
DISPLAY INVISIBLE (-200 1775);
FORCEPROP 1 LAST PATH I64
J 0
(-527 1900);
DISPLAY 0.872340 (-527 1900);
PAINT GREEN (-527 1900);
DISPLAY INVISIBLE (-527 1900);
FORCEADD TAP..1
(-525 2000);
FORCEPROP 3 LASTPIN (-575 2000) SIG_NAME M_G_CPU0_SB_DQ<17>
J 0
(-565 2010);
DISPLAY 0.659574 (-565 2010);
PAINT MONO (-565 2010);
DISPLAY INVISIBLE (-565 2010);
FORCEPROP 1 LASTPIN (-575 2000) BN 17
J 0
(-587 2008);
DISPLAY 0.680851 (-587 2008);
PAINT GREEN (-587 2008);
FORCEPROP 2 LAST CDS_LIB standard
J 0
(-525 2000);
PAINT MONO (-525 2000);
DISPLAY INVISIBLE (-525 2000);
FORCEPROP 1 LAST BODY_TYPE PLUMBING
J 0
(-525 2050);
DISPLAY 0.872340 (-525 2050);
PAINT GREEN (-525 2050);
DISPLAY INVISIBLE (-525 2050);
FORCEPROP 1 LAST HDL_TAP TRUE
J 0
(-200 1875);
DISPLAY 0.872340 (-200 1875);
DISPLAY INVISIBLE (-200 1875);
FORCEPROP 1 LAST PATH I65
J 0
(-527 2000);
DISPLAY 0.872340 (-527 2000);
PAINT GREEN (-527 2000);
DISPLAY INVISIBLE (-527 2000);
FORCEADD TAP..1
(-525 2050);
FORCEPROP 3 LASTPIN (-575 2050) SIG_NAME M_G_CPU0_SB_DQ<18>
J 0
(-565 2060);
DISPLAY 0.659574 (-565 2060);
PAINT MONO (-565 2060);
DISPLAY INVISIBLE (-565 2060);
FORCEPROP 1 LASTPIN (-575 2050) BN 18
J 0
(-587 2058);
DISPLAY 0.680851 (-587 2058);
PAINT GREEN (-587 2058);
FORCEPROP 2 LAST CDS_LIB standard
J 0
(-525 2050);
PAINT MONO (-525 2050);
DISPLAY INVISIBLE (-525 2050);
FORCEPROP 1 LAST BODY_TYPE PLUMBING
J 0
(-525 2100);
DISPLAY 0.872340 (-525 2100);
PAINT GREEN (-525 2100);
DISPLAY INVISIBLE (-525 2100);
FORCEPROP 1 LAST HDL_TAP TRUE
J 0
(-200 1925);
DISPLAY 0.872340 (-200 1925);
DISPLAY INVISIBLE (-200 1925);
FORCEPROP 1 LAST PATH I66
J 0
(-527 2050);
DISPLAY 0.872340 (-527 2050);
PAINT GREEN (-527 2050);
DISPLAY INVISIBLE (-527 2050);
FORCEADD TAP..1
(-525 2100);
FORCEPROP 3 LASTPIN (-575 2100) SIG_NAME M_G_CPU0_SB_DQ<19>
J 0
(-565 2110);
DISPLAY 0.659574 (-565 2110);
PAINT MONO (-565 2110);
DISPLAY INVISIBLE (-565 2110);
FORCEPROP 1 LASTPIN (-575 2100) BN 19
J 0
(-587 2108);
DISPLAY 0.680851 (-587 2108);
PAINT GREEN (-587 2108);
FORCEPROP 2 LAST CDS_LIB standard
J 0
(-525 2100);
PAINT MONO (-525 2100);
DISPLAY INVISIBLE (-525 2100);
FORCEPROP 1 LAST BODY_TYPE PLUMBING
J 0
(-525 2150);
DISPLAY 0.872340 (-525 2150);
PAINT GREEN (-525 2150);
DISPLAY INVISIBLE (-525 2150);
FORCEPROP 1 LAST HDL_TAP TRUE
J 0
(-200 1975);
DISPLAY 0.872340 (-200 1975);
DISPLAY INVISIBLE (-200 1975);
FORCEPROP 1 LAST PATH I67
J 0
(-527 2100);
DISPLAY 0.872340 (-527 2100);
PAINT GREEN (-527 2100);
DISPLAY INVISIBLE (-527 2100);
FORCEADD TAP..1
(-525 2150);
FORCEPROP 3 LASTPIN (-575 2150) SIG_NAME M_G_CPU0_SB_DQ<20>
J 0
(-565 2160);
DISPLAY 0.659574 (-565 2160);
PAINT MONO (-565 2160);
DISPLAY INVISIBLE (-565 2160);
FORCEPROP 1 LASTPIN (-575 2150) BN 20
J 0
(-587 2158);
DISPLAY 0.680851 (-587 2158);
PAINT GREEN (-587 2158);
FORCEPROP 2 LAST CDS_LIB standard
J 0
(-525 2150);
PAINT MONO (-525 2150);
DISPLAY INVISIBLE (-525 2150);
FORCEPROP 1 LAST BODY_TYPE PLUMBING
J 0
(-525 2200);
DISPLAY 0.872340 (-525 2200);
PAINT GREEN (-525 2200);
DISPLAY INVISIBLE (-525 2200);
FORCEPROP 1 LAST HDL_TAP TRUE
J 0
(-200 2025);
DISPLAY 0.872340 (-200 2025);
DISPLAY INVISIBLE (-200 2025);
FORCEPROP 1 LAST PATH I68
J 0
(-527 2150);
DISPLAY 0.872340 (-527 2150);
PAINT GREEN (-527 2150);
DISPLAY INVISIBLE (-527 2150);
FORCEADD TAP..1
(-525 2250);
FORCEPROP 3 LASTPIN (-575 2250) SIG_NAME M_G_CPU0_SB_DQ<22>
J 0
(-565 2260);
DISPLAY 0.659574 (-565 2260);
PAINT MONO (-565 2260);
DISPLAY INVISIBLE (-565 2260);
FORCEPROP 1 LASTPIN (-575 2250) BN 22
J 0
(-587 2258);
DISPLAY 0.680851 (-587 2258);
PAINT GREEN (-587 2258);
FORCEPROP 2 LAST CDS_LIB standard
J 0
(-525 2250);
DISPLAY INVISIBLE (-525 2250);
FORCEPROP 1 LAST BODY_TYPE PLUMBING
J 0
(-525 2300);
DISPLAY 0.872340 (-525 2300);
PAINT GREEN (-525 2300);
DISPLAY INVISIBLE (-525 2300);
FORCEPROP 1 LAST HDL_TAP TRUE
J 0
(-200 2125);
DISPLAY 0.872340 (-200 2125);
DISPLAY INVISIBLE (-200 2125);
FORCEPROP 1 LAST PATH I69
J 0
(-527 2250);
DISPLAY 0.872340 (-527 2250);
PAINT GREEN (-527 2250);
DISPLAY INVISIBLE (-527 2250);
FORCEADD OFFPAGE..1
(-3000 1800);
FORCEPROP 2 LAST $XR7 97 
J 0
(-3522 1764);
DISPLAY 0.638298 (-3522 1764);
PAINT MONO (-3522 1764);
FORCEPROP 2 LAST $XR6 96 
J 0
(-3432 1764);
DISPLAY 0.638298 (-3432 1764);
PAINT MONO (-3432 1764);
FORCEPROP 2 LAST $XR5 95 
J 0
(-3342 1764);
DISPLAY 0.638298 (-3342 1764);
PAINT MONO (-3342 1764);
FORCEPROP 2 LAST $XR4 93 
J 0
(-3252 1764);
DISPLAY 0.638298 (-3252 1764);
PAINT MONO (-3252 1764);
FORCEPROP 2 LAST $XR3 92 
J 0
(-3522 1800);
DISPLAY 0.638298 (-3522 1800);
PAINT MONO (-3522 1800);
FORCEPROP 2 LAST $XR2 91 
J 0
(-3432 1800);
DISPLAY 0.638298 (-3432 1800);
PAINT MONO (-3432 1800);
FORCEPROP 2 LAST $XR1 90 
J 0
(-3342 1800);
DISPLAY 0.638298 (-3342 1800);
PAINT MONO (-3342 1800);
FORCEPROP 2 LAST $XR0 229 
J 0
(-3252 1800);
DISPLAY 0.638298 (-3252 1800);
PAINT MONO (-3252 1800);
FORCEPROP 2 LAST CDS_LIB standard
J 0
(-3000 1800);
PAINT MONO (-3000 1800);
DISPLAY INVISIBLE (-3000 1800);
FORCEPROP 1 LAST OFFPAGE TRUE
J 0
(-2675 1675);
DISPLAY 0.872340 (-2675 1675);
DISPLAY INVISIBLE (-2675 1675);
FORCEPROP 1 LAST COMMENT_BODY TRUE
J 0
(-2875 1700);
DISPLAY 0.872340 (-2875 1700);
PAINT GREEN (-2875 1700);
DISPLAY INVISIBLE (-2875 1700);
FORCEPROP 2 LAST PATH I7
J 0
(-2950 1875);
DISPLAY 1.021277 (-2950 1875);
DISPLAY INVISIBLE (-2950 1875);
FORCEADD TAP..1
(-525 2200);
FORCEPROP 3 LASTPIN (-575 2200) SIG_NAME M_G_CPU0_SB_DQ<21>
J 0
(-565 2210);
DISPLAY 0.659574 (-565 2210);
PAINT MONO (-565 2210);
DISPLAY INVISIBLE (-565 2210);
FORCEPROP 1 LASTPIN (-575 2200) BN 21
J 0
(-587 2208);
DISPLAY 0.680851 (-587 2208);
PAINT GREEN (-587 2208);
FORCEPROP 2 LAST CDS_LIB standard
J 0
(-525 2200);
PAINT MONO (-525 2200);
DISPLAY INVISIBLE (-525 2200);
FORCEPROP 1 LAST BODY_TYPE PLUMBING
J 0
(-525 2250);
DISPLAY 0.872340 (-525 2250);
PAINT GREEN (-525 2250);
DISPLAY INVISIBLE (-525 2250);
FORCEPROP 1 LAST HDL_TAP TRUE
J 0
(-200 2075);
DISPLAY 0.872340 (-200 2075);
DISPLAY INVISIBLE (-200 2075);
FORCEPROP 1 LAST PATH I70
J 0
(-527 2200);
DISPLAY 0.872340 (-527 2200);
PAINT GREEN (-527 2200);
DISPLAY INVISIBLE (-527 2200);
FORCEADD TAP..1
(-525 2350);
FORCEPROP 3 LASTPIN (-575 2350) SIG_NAME M_G_CPU0_SB_DQ<24>
J 0
(-565 2360);
DISPLAY 0.659574 (-565 2360);
PAINT MONO (-565 2360);
DISPLAY INVISIBLE (-565 2360);
FORCEPROP 1 LASTPIN (-575 2350) BN 24
J 0
(-587 2358);
DISPLAY 0.680851 (-587 2358);
PAINT GREEN (-587 2358);
FORCEPROP 2 LAST CDS_LIB standard
J 0
(-525 2350);
DISPLAY INVISIBLE (-525 2350);
FORCEPROP 1 LAST BODY_TYPE PLUMBING
J 0
(-525 2400);
DISPLAY 0.872340 (-525 2400);
PAINT GREEN (-525 2400);
DISPLAY INVISIBLE (-525 2400);
FORCEPROP 1 LAST HDL_TAP TRUE
J 0
(-200 2225);
DISPLAY 0.872340 (-200 2225);
DISPLAY INVISIBLE (-200 2225);
FORCEPROP 1 LAST PATH I71
J 0
(-527 2350);
DISPLAY 0.872340 (-527 2350);
PAINT GREEN (-527 2350);
DISPLAY INVISIBLE (-527 2350);
FORCEADD TAP..1
(-525 2300);
FORCEPROP 3 LASTPIN (-575 2300) SIG_NAME M_G_CPU0_SB_DQ<23>
J 0
(-565 2310);
DISPLAY 0.659574 (-565 2310);
PAINT MONO (-565 2310);
DISPLAY INVISIBLE (-565 2310);
FORCEPROP 1 LASTPIN (-575 2300) BN 23
J 0
(-587 2308);
DISPLAY 0.680851 (-587 2308);
PAINT GREEN (-587 2308);
FORCEPROP 2 LAST CDS_LIB standard
J 0
(-525 2300);
DISPLAY INVISIBLE (-525 2300);
FORCEPROP 1 LAST BODY_TYPE PLUMBING
J 0
(-525 2350);
DISPLAY 0.872340 (-525 2350);
PAINT GREEN (-525 2350);
DISPLAY INVISIBLE (-525 2350);
FORCEPROP 1 LAST HDL_TAP TRUE
J 0
(-200 2175);
DISPLAY 0.872340 (-200 2175);
DISPLAY INVISIBLE (-200 2175);
FORCEPROP 1 LAST PATH I72
J 0
(-527 2300);
DISPLAY 0.872340 (-527 2300);
PAINT GREEN (-527 2300);
DISPLAY INVISIBLE (-527 2300);
FORCEADD TAP..1
(-525 2400);
FORCEPROP 3 LASTPIN (-575 2400) SIG_NAME M_G_CPU0_SB_DQ<25>
J 0
(-565 2410);
DISPLAY 0.659574 (-565 2410);
PAINT MONO (-565 2410);
DISPLAY INVISIBLE (-565 2410);
FORCEPROP 1 LASTPIN (-575 2400) BN 25
J 0
(-587 2408);
DISPLAY 0.680851 (-587 2408);
PAINT GREEN (-587 2408);
FORCEPROP 2 LAST CDS_LIB standard
J 0
(-525 2400);
DISPLAY INVISIBLE (-525 2400);
FORCEPROP 1 LAST BODY_TYPE PLUMBING
J 0
(-525 2450);
DISPLAY 0.872340 (-525 2450);
PAINT GREEN (-525 2450);
DISPLAY INVISIBLE (-525 2450);
FORCEPROP 1 LAST HDL_TAP TRUE
J 0
(-200 2275);
DISPLAY 0.872340 (-200 2275);
DISPLAY INVISIBLE (-200 2275);
FORCEPROP 1 LAST PATH I73
J 0
(-527 2400);
DISPLAY 0.872340 (-527 2400);
PAINT GREEN (-527 2400);
DISPLAY INVISIBLE (-527 2400);
FORCEADD TAP..1
(-525 2450);
FORCEPROP 3 LASTPIN (-575 2450) SIG_NAME M_G_CPU0_SB_DQ<26>
J 0
(-565 2460);
DISPLAY 0.659574 (-565 2460);
PAINT MONO (-565 2460);
DISPLAY INVISIBLE (-565 2460);
FORCEPROP 1 LASTPIN (-575 2450) BN 26
J 0
(-587 2458);
DISPLAY 0.680851 (-587 2458);
PAINT GREEN (-587 2458);
FORCEPROP 2 LAST CDS_LIB standard
J 0
(-525 2450);
DISPLAY INVISIBLE (-525 2450);
FORCEPROP 1 LAST BODY_TYPE PLUMBING
J 0
(-525 2500);
DISPLAY 0.872340 (-525 2500);
PAINT GREEN (-525 2500);
DISPLAY INVISIBLE (-525 2500);
FORCEPROP 1 LAST HDL_TAP TRUE
J 0
(-200 2325);
DISPLAY 0.872340 (-200 2325);
DISPLAY INVISIBLE (-200 2325);
FORCEPROP 1 LAST PATH I74
J 0
(-527 2450);
DISPLAY 0.872340 (-527 2450);
PAINT GREEN (-527 2450);
DISPLAY INVISIBLE (-527 2450);
FORCEADD TAP..1
(-525 2500);
FORCEPROP 3 LASTPIN (-575 2500) SIG_NAME M_G_CPU0_SB_DQ<27>
J 0
(-565 2510);
DISPLAY 0.659574 (-565 2510);
PAINT MONO (-565 2510);
DISPLAY INVISIBLE (-565 2510);
FORCEPROP 1 LASTPIN (-575 2500) BN 27
J 0
(-587 2508);
DISPLAY 0.680851 (-587 2508);
PAINT GREEN (-587 2508);
FORCEPROP 2 LAST CDS_LIB standard
J 0
(-525 2500);
DISPLAY INVISIBLE (-525 2500);
FORCEPROP 1 LAST BODY_TYPE PLUMBING
J 0
(-525 2550);
DISPLAY 0.872340 (-525 2550);
PAINT GREEN (-525 2550);
DISPLAY INVISIBLE (-525 2550);
FORCEPROP 1 LAST HDL_TAP TRUE
J 0
(-200 2375);
DISPLAY 0.872340 (-200 2375);
DISPLAY INVISIBLE (-200 2375);
FORCEPROP 1 LAST PATH I75
J 0
(-527 2500);
DISPLAY 0.872340 (-527 2500);
PAINT GREEN (-527 2500);
DISPLAY INVISIBLE (-527 2500);
FORCEADD TAP..1
(-525 2600);
FORCEPROP 3 LASTPIN (-575 2600) SIG_NAME M_G_CPU0_SB_DQ<29>
J 0
(-565 2610);
DISPLAY 0.659574 (-565 2610);
PAINT MONO (-565 2610);
DISPLAY INVISIBLE (-565 2610);
FORCEPROP 1 LASTPIN (-575 2600) BN 29
J 0
(-587 2608);
DISPLAY 0.680851 (-587 2608);
PAINT GREEN (-587 2608);
FORCEPROP 2 LAST CDS_LIB standard
J 0
(-525 2600);
DISPLAY INVISIBLE (-525 2600);
FORCEPROP 1 LAST BODY_TYPE PLUMBING
J 0
(-525 2650);
DISPLAY 0.872340 (-525 2650);
PAINT GREEN (-525 2650);
DISPLAY INVISIBLE (-525 2650);
FORCEPROP 1 LAST HDL_TAP TRUE
J 0
(-200 2475);
DISPLAY 0.872340 (-200 2475);
DISPLAY INVISIBLE (-200 2475);
FORCEPROP 1 LAST PATH I76
J 0
(-527 2600);
DISPLAY 0.872340 (-527 2600);
PAINT GREEN (-527 2600);
DISPLAY INVISIBLE (-527 2600);
FORCEADD TAP..1
(-525 2550);
FORCEPROP 3 LASTPIN (-575 2550) SIG_NAME M_G_CPU0_SB_DQ<28>
J 0
(-565 2560);
DISPLAY 0.659574 (-565 2560);
PAINT MONO (-565 2560);
DISPLAY INVISIBLE (-565 2560);
FORCEPROP 1 LASTPIN (-575 2550) BN 28
J 0
(-587 2558);
DISPLAY 0.680851 (-587 2558);
PAINT GREEN (-587 2558);
FORCEPROP 2 LAST CDS_LIB standard
J 0
(-525 2550);
DISPLAY INVISIBLE (-525 2550);
FORCEPROP 1 LAST BODY_TYPE PLUMBING
J 0
(-525 2600);
DISPLAY 0.872340 (-525 2600);
PAINT GREEN (-525 2600);
DISPLAY INVISIBLE (-525 2600);
FORCEPROP 1 LAST HDL_TAP TRUE
J 0
(-200 2425);
DISPLAY 0.872340 (-200 2425);
DISPLAY INVISIBLE (-200 2425);
FORCEPROP 1 LAST PATH I77
J 0
(-527 2550);
DISPLAY 0.872340 (-527 2550);
PAINT GREEN (-527 2550);
DISPLAY INVISIBLE (-527 2550);
FORCEADD TAP..1
(-525 2700);
FORCEPROP 3 LASTPIN (-575 2700) SIG_NAME M_G_CPU0_SB_DQ<31>
J 0
(-565 2710);
DISPLAY 0.659574 (-565 2710);
PAINT MONO (-565 2710);
DISPLAY INVISIBLE (-565 2710);
FORCEPROP 1 LASTPIN (-575 2700) BN 31
J 0
(-587 2708);
DISPLAY 0.680851 (-587 2708);
PAINT GREEN (-587 2708);
FORCEPROP 2 LAST CDS_LIB standard
J 0
(-525 2700);
DISPLAY INVISIBLE (-525 2700);
FORCEPROP 1 LAST BODY_TYPE PLUMBING
J 0
(-525 2750);
DISPLAY 0.872340 (-525 2750);
PAINT GREEN (-525 2750);
DISPLAY INVISIBLE (-525 2750);
FORCEPROP 1 LAST HDL_TAP TRUE
J 0
(-200 2575);
DISPLAY 0.872340 (-200 2575);
DISPLAY INVISIBLE (-200 2575);
FORCEPROP 1 LAST PATH I78
J 0
(-527 2700);
DISPLAY 0.872340 (-527 2700);
PAINT GREEN (-527 2700);
DISPLAY INVISIBLE (-527 2700);
FORCEADD TAP..1
(-525 2650);
FORCEPROP 3 LASTPIN (-575 2650) SIG_NAME M_G_CPU0_SB_DQ<30>
J 0
(-565 2660);
DISPLAY 0.659574 (-565 2660);
PAINT MONO (-565 2660);
DISPLAY INVISIBLE (-565 2660);
FORCEPROP 1 LASTPIN (-575 2650) BN 30
J 0
(-587 2658);
DISPLAY 0.680851 (-587 2658);
PAINT GREEN (-587 2658);
FORCEPROP 2 LAST CDS_LIB standard
J 0
(-525 2650);
DISPLAY INVISIBLE (-525 2650);
FORCEPROP 1 LAST BODY_TYPE PLUMBING
J 0
(-525 2700);
DISPLAY 0.872340 (-525 2700);
PAINT GREEN (-525 2700);
DISPLAY INVISIBLE (-525 2700);
FORCEPROP 1 LAST HDL_TAP TRUE
J 0
(-200 2525);
DISPLAY 0.872340 (-200 2525);
DISPLAY INVISIBLE (-200 2525);
FORCEPROP 1 LAST PATH I79
J 0
(-527 2650);
DISPLAY 0.872340 (-527 2650);
PAINT GREEN (-527 2650);
DISPLAY INVISIBLE (-527 2650);
FORCEADD OFFPAGE..1
(-3100 2000);
FORCEPROP 2 LAST $XR1 95 
J 0
(-3411 2000);
DISPLAY 0.638298 (-3411 2000);
PAINT MONO (-3411 2000);
FORCEPROP 2 LAST $XR0 26 
J 0
(-3321 2000);
DISPLAY 0.638298 (-3321 2000);
PAINT MONO (-3321 2000);
FORCEPROP 2 LAST CDS_LIB standard
J 0
(-3100 2000);
PAINT MONO (-3100 2000);
DISPLAY INVISIBLE (-3100 2000);
FORCEPROP 1 LAST OFFPAGE TRUE
J 0
(-2775 1875);
DISPLAY 0.872340 (-2775 1875);
DISPLAY INVISIBLE (-2775 1875);
FORCEPROP 1 LAST COMMENT_BODY TRUE
J 0
(-2975 1900);
DISPLAY 0.872340 (-2975 1900);
PAINT GREEN (-2975 1900);
DISPLAY INVISIBLE (-2975 1900);
FORCEPROP 2 LAST PATH I8
J 0
(-3050 2075);
DISPLAY 1.021277 (-3050 2075);
DISPLAY INVISIBLE (-3050 2075);
FORCEADD TAP..1
(-525 2800);
FORCEPROP 3 LASTPIN (-575 2800) SIG_NAME M_G_CPU0_SA_DQ<0>
J 0
(-565 2810);
DISPLAY 0.659574 (-565 2810);
PAINT MONO (-565 2810);
DISPLAY INVISIBLE (-565 2810);
FORCEPROP 1 LASTPIN (-575 2800) BN 0
J 0
(-587 2808);
DISPLAY 0.680851 (-587 2808);
PAINT GREEN (-587 2808);
FORCEPROP 2 LAST CDS_LIB standard
J 0
(-525 2800);
PAINT MONO (-525 2800);
DISPLAY INVISIBLE (-525 2800);
FORCEPROP 1 LAST BODY_TYPE PLUMBING
J 0
(-525 2850);
DISPLAY 0.872340 (-525 2850);
PAINT GREEN (-525 2850);
DISPLAY INVISIBLE (-525 2850);
FORCEPROP 1 LAST HDL_TAP TRUE
J 0
(-200 2675);
DISPLAY 0.872340 (-200 2675);
DISPLAY INVISIBLE (-200 2675);
FORCEPROP 1 LAST PATH I80
J 0
(-527 2800);
DISPLAY 0.872340 (-527 2800);
PAINT GREEN (-527 2800);
DISPLAY INVISIBLE (-527 2800);
FORCEADD TAP..1
(-525 2850);
FORCEPROP 3 LASTPIN (-575 2850) SIG_NAME M_G_CPU0_SA_DQ<1>
J 0
(-565 2860);
DISPLAY 0.659574 (-565 2860);
PAINT MONO (-565 2860);
DISPLAY INVISIBLE (-565 2860);
FORCEPROP 1 LASTPIN (-575 2850) BN 1
J 0
(-587 2858);
DISPLAY 0.680851 (-587 2858);
PAINT GREEN (-587 2858);
FORCEPROP 2 LAST CDS_LIB standard
J 0
(-525 2850);
PAINT MONO (-525 2850);
DISPLAY INVISIBLE (-525 2850);
FORCEPROP 1 LAST BODY_TYPE PLUMBING
J 0
(-525 2900);
DISPLAY 0.872340 (-525 2900);
PAINT GREEN (-525 2900);
DISPLAY INVISIBLE (-525 2900);
FORCEPROP 1 LAST HDL_TAP TRUE
J 0
(-200 2725);
DISPLAY 0.872340 (-200 2725);
DISPLAY INVISIBLE (-200 2725);
FORCEPROP 1 LAST PATH I81
J 0
(-527 2850);
DISPLAY 0.872340 (-527 2850);
PAINT GREEN (-527 2850);
DISPLAY INVISIBLE (-527 2850);
FORCEADD TAP..1
(-525 2950);
FORCEPROP 3 LASTPIN (-575 2950) SIG_NAME M_G_CPU0_SA_DQ<3>
J 0
(-565 2960);
DISPLAY 0.659574 (-565 2960);
PAINT MONO (-565 2960);
DISPLAY INVISIBLE (-565 2960);
FORCEPROP 1 LASTPIN (-575 2950) BN 3
J 0
(-587 2958);
DISPLAY 0.680851 (-587 2958);
PAINT GREEN (-587 2958);
FORCEPROP 2 LAST CDS_LIB standard
J 0
(-525 2950);
PAINT MONO (-525 2950);
DISPLAY INVISIBLE (-525 2950);
FORCEPROP 1 LAST BODY_TYPE PLUMBING
J 0
(-525 3000);
DISPLAY 0.872340 (-525 3000);
PAINT GREEN (-525 3000);
DISPLAY INVISIBLE (-525 3000);
FORCEPROP 1 LAST HDL_TAP TRUE
J 0
(-200 2825);
DISPLAY 0.872340 (-200 2825);
DISPLAY INVISIBLE (-200 2825);
FORCEPROP 1 LAST PATH I82
J 0
(-527 2950);
DISPLAY 0.872340 (-527 2950);
PAINT GREEN (-527 2950);
DISPLAY INVISIBLE (-527 2950);
FORCEADD TAP..1
(-525 2900);
FORCEPROP 3 LASTPIN (-575 2900) SIG_NAME M_G_CPU0_SA_DQ<2>
J 0
(-565 2910);
DISPLAY 0.659574 (-565 2910);
PAINT MONO (-565 2910);
DISPLAY INVISIBLE (-565 2910);
FORCEPROP 1 LASTPIN (-575 2900) BN 2
J 0
(-587 2908);
DISPLAY 0.680851 (-587 2908);
PAINT GREEN (-587 2908);
FORCEPROP 2 LAST CDS_LIB standard
J 0
(-525 2900);
PAINT MONO (-525 2900);
DISPLAY INVISIBLE (-525 2900);
FORCEPROP 1 LAST BODY_TYPE PLUMBING
J 0
(-525 2950);
DISPLAY 0.872340 (-525 2950);
PAINT GREEN (-525 2950);
DISPLAY INVISIBLE (-525 2950);
FORCEPROP 1 LAST HDL_TAP TRUE
J 0
(-200 2775);
DISPLAY 0.872340 (-200 2775);
DISPLAY INVISIBLE (-200 2775);
FORCEPROP 1 LAST PATH I83
J 0
(-527 2900);
DISPLAY 0.872340 (-527 2900);
PAINT GREEN (-527 2900);
DISPLAY INVISIBLE (-527 2900);
FORCEADD TAP..1
(-525 3000);
FORCEPROP 3 LASTPIN (-575 3000) SIG_NAME M_G_CPU0_SA_DQ<4>
J 0
(-565 3010);
DISPLAY 0.659574 (-565 3010);
PAINT MONO (-565 3010);
DISPLAY INVISIBLE (-565 3010);
FORCEPROP 1 LASTPIN (-575 3000) BN 4
J 0
(-587 3008);
DISPLAY 0.680851 (-587 3008);
PAINT GREEN (-587 3008);
FORCEPROP 2 LAST CDS_LIB standard
J 0
(-525 3000);
PAINT MONO (-525 3000);
DISPLAY INVISIBLE (-525 3000);
FORCEPROP 1 LAST BODY_TYPE PLUMBING
J 0
(-525 3050);
DISPLAY 0.872340 (-525 3050);
PAINT GREEN (-525 3050);
DISPLAY INVISIBLE (-525 3050);
FORCEPROP 1 LAST HDL_TAP TRUE
J 0
(-200 2875);
DISPLAY 0.872340 (-200 2875);
DISPLAY INVISIBLE (-200 2875);
FORCEPROP 1 LAST PATH I84
J 0
(-527 3000);
DISPLAY 0.872340 (-527 3000);
PAINT GREEN (-527 3000);
DISPLAY INVISIBLE (-527 3000);
FORCEADD TAP..1
(-525 3100);
FORCEPROP 3 LASTPIN (-575 3100) SIG_NAME M_G_CPU0_SA_DQ<6>
J 0
(-565 3110);
DISPLAY 0.659574 (-565 3110);
PAINT MONO (-565 3110);
DISPLAY INVISIBLE (-565 3110);
FORCEPROP 1 LASTPIN (-575 3100) BN 6
J 0
(-587 3108);
DISPLAY 0.680851 (-587 3108);
PAINT GREEN (-587 3108);
FORCEPROP 2 LAST CDS_LIB standard
J 0
(-525 3100);
PAINT MONO (-525 3100);
DISPLAY INVISIBLE (-525 3100);
FORCEPROP 1 LAST BODY_TYPE PLUMBING
J 0
(-525 3150);
DISPLAY 0.872340 (-525 3150);
PAINT GREEN (-525 3150);
DISPLAY INVISIBLE (-525 3150);
FORCEPROP 1 LAST HDL_TAP TRUE
J 0
(-200 2975);
DISPLAY 0.872340 (-200 2975);
DISPLAY INVISIBLE (-200 2975);
FORCEPROP 1 LAST PATH I85
J 0
(-527 3100);
DISPLAY 0.872340 (-527 3100);
PAINT GREEN (-527 3100);
DISPLAY INVISIBLE (-527 3100);
FORCEADD TAP..1
(-525 3050);
FORCEPROP 3 LASTPIN (-575 3050) SIG_NAME M_G_CPU0_SA_DQ<5>
J 0
(-565 3060);
DISPLAY 0.659574 (-565 3060);
PAINT MONO (-565 3060);
DISPLAY INVISIBLE (-565 3060);
FORCEPROP 1 LASTPIN (-575 3050) BN 5
J 0
(-587 3058);
DISPLAY 0.680851 (-587 3058);
PAINT GREEN (-587 3058);
FORCEPROP 2 LAST CDS_LIB standard
J 0
(-525 3050);
PAINT MONO (-525 3050);
DISPLAY INVISIBLE (-525 3050);
FORCEPROP 1 LAST BODY_TYPE PLUMBING
J 0
(-525 3100);
DISPLAY 0.872340 (-525 3100);
PAINT GREEN (-525 3100);
DISPLAY INVISIBLE (-525 3100);
FORCEPROP 1 LAST HDL_TAP TRUE
J 0
(-200 2925);
DISPLAY 0.872340 (-200 2925);
DISPLAY INVISIBLE (-200 2925);
FORCEPROP 1 LAST PATH I86
J 0
(-527 3050);
DISPLAY 0.872340 (-527 3050);
PAINT GREEN (-527 3050);
DISPLAY INVISIBLE (-527 3050);
FORCEADD TAP..1
(-525 3150);
FORCEPROP 3 LASTPIN (-575 3150) SIG_NAME M_G_CPU0_SA_DQ<7>
J 0
(-565 3160);
DISPLAY 0.659574 (-565 3160);
PAINT MONO (-565 3160);
DISPLAY INVISIBLE (-565 3160);
FORCEPROP 1 LASTPIN (-575 3150) BN 7
J 0
(-587 3158);
DISPLAY 0.680851 (-587 3158);
PAINT GREEN (-587 3158);
FORCEPROP 2 LAST CDS_LIB standard
J 0
(-525 3150);
PAINT MONO (-525 3150);
DISPLAY INVISIBLE (-525 3150);
FORCEPROP 1 LAST BODY_TYPE PLUMBING
J 0
(-525 3200);
DISPLAY 0.872340 (-525 3200);
PAINT GREEN (-525 3200);
DISPLAY INVISIBLE (-525 3200);
FORCEPROP 1 LAST HDL_TAP TRUE
J 0
(-200 3025);
DISPLAY 0.872340 (-200 3025);
DISPLAY INVISIBLE (-200 3025);
FORCEPROP 1 LAST PATH I87
J 0
(-527 3150);
DISPLAY 0.872340 (-527 3150);
PAINT GREEN (-527 3150);
DISPLAY INVISIBLE (-527 3150);
FORCEADD TAP..1
(-525 3250);
FORCEPROP 3 LASTPIN (-575 3250) SIG_NAME M_G_CPU0_SA_DQ<9>
J 0
(-565 3260);
DISPLAY 0.659574 (-565 3260);
PAINT MONO (-565 3260);
DISPLAY INVISIBLE (-565 3260);
FORCEPROP 1 LASTPIN (-575 3250) BN 9
J 0
(-587 3258);
DISPLAY 0.680851 (-587 3258);
PAINT GREEN (-587 3258);
FORCEPROP 2 LAST CDS_LIB standard
J 0
(-525 3250);
PAINT MONO (-525 3250);
DISPLAY INVISIBLE (-525 3250);
FORCEPROP 1 LAST BODY_TYPE PLUMBING
J 0
(-525 3300);
DISPLAY 0.872340 (-525 3300);
PAINT GREEN (-525 3300);
DISPLAY INVISIBLE (-525 3300);
FORCEPROP 1 LAST HDL_TAP TRUE
J 0
(-200 3125);
DISPLAY 0.872340 (-200 3125);
DISPLAY INVISIBLE (-200 3125);
FORCEPROP 1 LAST PATH I88
J 0
(-527 3250);
DISPLAY 0.872340 (-527 3250);
PAINT GREEN (-527 3250);
DISPLAY INVISIBLE (-527 3250);
FORCEADD TAP..1
(-525 3200);
FORCEPROP 3 LASTPIN (-575 3200) SIG_NAME M_G_CPU0_SA_DQ<8>
J 0
(-565 3210);
DISPLAY 0.659574 (-565 3210);
PAINT MONO (-565 3210);
DISPLAY INVISIBLE (-565 3210);
FORCEPROP 1 LASTPIN (-575 3200) BN 8
J 0
(-587 3208);
DISPLAY 0.680851 (-587 3208);
PAINT GREEN (-587 3208);
FORCEPROP 2 LAST CDS_LIB standard
J 0
(-525 3200);
PAINT MONO (-525 3200);
DISPLAY INVISIBLE (-525 3200);
FORCEPROP 1 LAST BODY_TYPE PLUMBING
J 0
(-525 3250);
DISPLAY 0.872340 (-525 3250);
PAINT GREEN (-525 3250);
DISPLAY INVISIBLE (-525 3250);
FORCEPROP 1 LAST HDL_TAP TRUE
J 0
(-200 3075);
DISPLAY 0.872340 (-200 3075);
DISPLAY INVISIBLE (-200 3075);
FORCEPROP 1 LAST PATH I89
J 0
(-527 3200);
DISPLAY 0.872340 (-527 3200);
PAINT GREEN (-527 3200);
DISPLAY INVISIBLE (-527 3200);
FORCEADD UNIVERSAL_GND..1
(-1950 -25);
FORCEPROP 3 LASTPIN (-1950 25) SIG_NAME GND\g
J 0
(-1940 35);
DISPLAY 0.659574 (-1940 35);
PAINT MONO (-1940 35);
DISPLAY INVISIBLE (-1940 35);
FORCEPROP 2 LAST CDS_LIB logical_power
J 0
(-1950 -25);
PAINT MONO (-1950 -25);
DISPLAY INVISIBLE (-1950 -25);
FORCEPROP 1 LAST HDL_POWER GND
J 1
(-1925 -100);
DISPLAY 0.872340 (-1925 -100);
PAINT GREEN (-1925 -100);
DISPLAY INVISIBLE (-1925 -100);
FORCEPROP 1 LAST PATH I9
J 0
(-1875 -25);
DISPLAY 0.872340 (-1875 -25);
PAINT AQUA (-1875 -25);
DISPLAY INVISIBLE (-1875 -25);
FORCEADD TAP..1
(-525 3300);
FORCEPROP 3 LASTPIN (-575 3300) SIG_NAME M_G_CPU0_SA_DQ<10>
J 0
(-565 3310);
DISPLAY 0.659574 (-565 3310);
PAINT MONO (-565 3310);
DISPLAY INVISIBLE (-565 3310);
FORCEPROP 1 LASTPIN (-575 3300) BN 10
J 0
(-587 3308);
DISPLAY 0.680851 (-587 3308);
PAINT GREEN (-587 3308);
FORCEPROP 2 LAST CDS_LIB standard
J 0
(-525 3300);
PAINT MONO (-525 3300);
DISPLAY INVISIBLE (-525 3300);
FORCEPROP 1 LAST BODY_TYPE PLUMBING
J 0
(-525 3350);
DISPLAY 0.872340 (-525 3350);
PAINT GREEN (-525 3350);
DISPLAY INVISIBLE (-525 3350);
FORCEPROP 1 LAST HDL_TAP TRUE
J 0
(-200 3175);
DISPLAY 0.872340 (-200 3175);
DISPLAY INVISIBLE (-200 3175);
FORCEPROP 1 LAST PATH I90
J 0
(-527 3300);
DISPLAY 0.872340 (-527 3300);
PAINT GREEN (-527 3300);
DISPLAY INVISIBLE (-527 3300);
FORCEADD TAP..1
(-525 3350);
FORCEPROP 3 LASTPIN (-575 3350) SIG_NAME M_G_CPU0_SA_DQ<11>
J 0
(-565 3360);
DISPLAY 0.659574 (-565 3360);
PAINT MONO (-565 3360);
DISPLAY INVISIBLE (-565 3360);
FORCEPROP 1 LASTPIN (-575 3350) BN 11
J 0
(-587 3358);
DISPLAY 0.680851 (-587 3358);
PAINT GREEN (-587 3358);
FORCEPROP 2 LAST CDS_LIB standard
J 0
(-525 3350);
PAINT MONO (-525 3350);
DISPLAY INVISIBLE (-525 3350);
FORCEPROP 1 LAST BODY_TYPE PLUMBING
J 0
(-525 3400);
DISPLAY 0.872340 (-525 3400);
PAINT GREEN (-525 3400);
DISPLAY INVISIBLE (-525 3400);
FORCEPROP 1 LAST HDL_TAP TRUE
J 0
(-200 3225);
DISPLAY 0.872340 (-200 3225);
DISPLAY INVISIBLE (-200 3225);
FORCEPROP 1 LAST PATH I91
J 0
(-527 3350);
DISPLAY 0.872340 (-527 3350);
PAINT GREEN (-527 3350);
DISPLAY INVISIBLE (-527 3350);
FORCEADD TAP..1
(-525 3400);
FORCEPROP 3 LASTPIN (-575 3400) SIG_NAME M_G_CPU0_SA_DQ<12>
J 0
(-565 3410);
DISPLAY 0.659574 (-565 3410);
PAINT MONO (-565 3410);
DISPLAY INVISIBLE (-565 3410);
FORCEPROP 1 LASTPIN (-575 3400) BN 12
J 0
(-587 3408);
DISPLAY 0.680851 (-587 3408);
PAINT GREEN (-587 3408);
FORCEPROP 2 LAST CDS_LIB standard
J 0
(-525 3400);
PAINT MONO (-525 3400);
DISPLAY INVISIBLE (-525 3400);
FORCEPROP 1 LAST BODY_TYPE PLUMBING
J 0
(-525 3450);
DISPLAY 0.872340 (-525 3450);
PAINT GREEN (-525 3450);
DISPLAY INVISIBLE (-525 3450);
FORCEPROP 1 LAST HDL_TAP TRUE
J 0
(-200 3275);
DISPLAY 0.872340 (-200 3275);
DISPLAY INVISIBLE (-200 3275);
FORCEPROP 1 LAST PATH I92
J 0
(-527 3400);
DISPLAY 0.872340 (-527 3400);
PAINT GREEN (-527 3400);
DISPLAY INVISIBLE (-527 3400);
FORCEADD TAP..1
(-525 3500);
FORCEPROP 3 LASTPIN (-575 3500) SIG_NAME M_G_CPU0_SA_DQ<14>
J 0
(-565 3510);
DISPLAY 0.659574 (-565 3510);
PAINT MONO (-565 3510);
DISPLAY INVISIBLE (-565 3510);
FORCEPROP 1 LASTPIN (-575 3500) BN 14
J 0
(-587 3508);
DISPLAY 0.680851 (-587 3508);
PAINT GREEN (-587 3508);
FORCEPROP 2 LAST CDS_LIB standard
J 0
(-525 3500);
PAINT MONO (-525 3500);
DISPLAY INVISIBLE (-525 3500);
FORCEPROP 1 LAST BODY_TYPE PLUMBING
J 0
(-525 3550);
DISPLAY 0.872340 (-525 3550);
PAINT GREEN (-525 3550);
DISPLAY INVISIBLE (-525 3550);
FORCEPROP 1 LAST HDL_TAP TRUE
J 0
(-200 3375);
DISPLAY 0.872340 (-200 3375);
DISPLAY INVISIBLE (-200 3375);
FORCEPROP 1 LAST PATH I93
J 0
(-527 3500);
DISPLAY 0.872340 (-527 3500);
PAINT GREEN (-527 3500);
DISPLAY INVISIBLE (-527 3500);
FORCEADD TAP..1
(-525 3450);
FORCEPROP 3 LASTPIN (-575 3450) SIG_NAME M_G_CPU0_SA_DQ<13>
J 0
(-565 3460);
DISPLAY 0.659574 (-565 3460);
PAINT MONO (-565 3460);
DISPLAY INVISIBLE (-565 3460);
FORCEPROP 1 LASTPIN (-575 3450) BN 13
J 0
(-587 3458);
DISPLAY 0.680851 (-587 3458);
PAINT GREEN (-587 3458);
FORCEPROP 2 LAST CDS_LIB standard
J 0
(-525 3450);
PAINT MONO (-525 3450);
DISPLAY INVISIBLE (-525 3450);
FORCEPROP 1 LAST BODY_TYPE PLUMBING
J 0
(-525 3500);
DISPLAY 0.872340 (-525 3500);
PAINT GREEN (-525 3500);
DISPLAY INVISIBLE (-525 3500);
FORCEPROP 1 LAST HDL_TAP TRUE
J 0
(-200 3325);
DISPLAY 0.872340 (-200 3325);
DISPLAY INVISIBLE (-200 3325);
FORCEPROP 1 LAST PATH I94
J 0
(-527 3450);
DISPLAY 0.872340 (-527 3450);
PAINT GREEN (-527 3450);
DISPLAY INVISIBLE (-527 3450);
FORCEADD TAP..1
(-525 3550);
FORCEPROP 3 LASTPIN (-575 3550) SIG_NAME M_G_CPU0_SA_DQ<15>
J 0
(-565 3560);
DISPLAY 0.659574 (-565 3560);
PAINT MONO (-565 3560);
DISPLAY INVISIBLE (-565 3560);
FORCEPROP 1 LASTPIN (-575 3550) BN 15
J 0
(-587 3558);
DISPLAY 0.680851 (-587 3558);
PAINT GREEN (-587 3558);
FORCEPROP 2 LAST CDS_LIB standard
J 0
(-525 3550);
PAINT MONO (-525 3550);
DISPLAY INVISIBLE (-525 3550);
FORCEPROP 1 LAST BODY_TYPE PLUMBING
J 0
(-525 3600);
DISPLAY 0.872340 (-525 3600);
PAINT GREEN (-525 3600);
DISPLAY INVISIBLE (-525 3600);
FORCEPROP 1 LAST HDL_TAP TRUE
J 0
(-200 3425);
DISPLAY 0.872340 (-200 3425);
DISPLAY INVISIBLE (-200 3425);
FORCEPROP 1 LAST PATH I95
J 0
(-527 3550);
DISPLAY 0.872340 (-527 3550);
PAINT GREEN (-527 3550);
DISPLAY INVISIBLE (-527 3550);
FORCEADD TAP..1
(-525 3600);
FORCEPROP 3 LASTPIN (-575 3600) SIG_NAME M_G_CPU0_SA_DQ<16>
J 0
(-565 3610);
DISPLAY 0.659574 (-565 3610);
PAINT MONO (-565 3610);
DISPLAY INVISIBLE (-565 3610);
FORCEPROP 1 LASTPIN (-575 3600) BN 16
J 0
(-587 3608);
DISPLAY 0.680851 (-587 3608);
PAINT GREEN (-587 3608);
FORCEPROP 2 LAST CDS_LIB standard
J 0
(-525 3600);
PAINT MONO (-525 3600);
DISPLAY INVISIBLE (-525 3600);
FORCEPROP 1 LAST BODY_TYPE PLUMBING
J 0
(-525 3650);
DISPLAY 0.872340 (-525 3650);
PAINT GREEN (-525 3650);
DISPLAY INVISIBLE (-525 3650);
FORCEPROP 1 LAST HDL_TAP TRUE
J 0
(-200 3475);
DISPLAY 0.872340 (-200 3475);
DISPLAY INVISIBLE (-200 3475);
FORCEPROP 1 LAST PATH I96
J 0
(-527 3600);
DISPLAY 0.872340 (-527 3600);
PAINT GREEN (-527 3600);
DISPLAY INVISIBLE (-527 3600);
FORCEADD TAP..1
(-525 3650);
FORCEPROP 3 LASTPIN (-575 3650) SIG_NAME M_G_CPU0_SA_DQ<17>
J 0
(-565 3660);
DISPLAY 0.659574 (-565 3660);
PAINT MONO (-565 3660);
DISPLAY INVISIBLE (-565 3660);
FORCEPROP 1 LASTPIN (-575 3650) BN 17
J 0
(-587 3658);
DISPLAY 0.680851 (-587 3658);
PAINT GREEN (-587 3658);
FORCEPROP 2 LAST CDS_LIB standard
J 0
(-525 3650);
PAINT MONO (-525 3650);
DISPLAY INVISIBLE (-525 3650);
FORCEPROP 1 LAST BODY_TYPE PLUMBING
J 0
(-525 3700);
DISPLAY 0.872340 (-525 3700);
PAINT GREEN (-525 3700);
DISPLAY INVISIBLE (-525 3700);
FORCEPROP 1 LAST HDL_TAP TRUE
J 0
(-200 3525);
DISPLAY 0.872340 (-200 3525);
DISPLAY INVISIBLE (-200 3525);
FORCEPROP 1 LAST PATH I97
J 0
(-527 3650);
DISPLAY 0.872340 (-527 3650);
PAINT GREEN (-527 3650);
DISPLAY INVISIBLE (-527 3650);
FORCEADD TAP..1
(-525 3750);
FORCEPROP 3 LASTPIN (-575 3750) SIG_NAME M_G_CPU0_SA_DQ<19>
J 0
(-565 3760);
DISPLAY 0.659574 (-565 3760);
PAINT MONO (-565 3760);
DISPLAY INVISIBLE (-565 3760);
FORCEPROP 1 LASTPIN (-575 3750) BN 19
J 0
(-587 3758);
DISPLAY 0.680851 (-587 3758);
PAINT GREEN (-587 3758);
FORCEPROP 2 LAST CDS_LIB standard
J 0
(-525 3750);
PAINT MONO (-525 3750);
DISPLAY INVISIBLE (-525 3750);
FORCEPROP 1 LAST BODY_TYPE PLUMBING
J 0
(-525 3800);
DISPLAY 0.872340 (-525 3800);
PAINT GREEN (-525 3800);
DISPLAY INVISIBLE (-525 3800);
FORCEPROP 1 LAST HDL_TAP TRUE
J 0
(-200 3625);
DISPLAY 0.872340 (-200 3625);
DISPLAY INVISIBLE (-200 3625);
FORCEPROP 1 LAST PATH I98
J 0
(-527 3750);
DISPLAY 0.872340 (-527 3750);
PAINT GREEN (-527 3750);
DISPLAY INVISIBLE (-527 3750);
FORCEADD TAP..1
(-525 3700);
FORCEPROP 3 LASTPIN (-575 3700) SIG_NAME M_G_CPU0_SA_DQ<18>
J 0
(-565 3710);
DISPLAY 0.659574 (-565 3710);
PAINT MONO (-565 3710);
DISPLAY INVISIBLE (-565 3710);
FORCEPROP 1 LASTPIN (-575 3700) BN 18
J 0
(-587 3708);
DISPLAY 0.680851 (-587 3708);
PAINT GREEN (-587 3708);
FORCEPROP 2 LAST CDS_LIB standard
J 0
(-525 3700);
PAINT MONO (-525 3700);
DISPLAY INVISIBLE (-525 3700);
FORCEPROP 1 LAST BODY_TYPE PLUMBING
J 0
(-525 3750);
DISPLAY 0.872340 (-525 3750);
PAINT GREEN (-525 3750);
DISPLAY INVISIBLE (-525 3750);
FORCEPROP 1 LAST HDL_TAP TRUE
J 0
(-200 3575);
DISPLAY 0.872340 (-200 3575);
DISPLAY INVISIBLE (-200 3575);
FORCEPROP 1 LAST PATH I99
J 0
(-527 3700);
DISPLAY 0.872340 (-527 3700);
PAINT GREEN (-527 3700);
DISPLAY INVISIBLE (-527 3700);
FORCEADD CAD_NOTE..1
(1325 -100);
FORCEPROP 0 LAST S1 PLACE THE BYPASS CAPS CLOSE TO DIMM
J 0
(1200 -225);
DISPLAY 1.021277 (1200 -225);
PAINT WHITE (1200 -225);
FORCEPROP 2 LAST CDS_LIB logical_power
J 0
(1325 -100);
PAINT MONO (1325 -100);
DISPLAY INVISIBLE (1325 -100);
FORCEPROP 1 LAST COMMENT_BODY TRUE
J 0
(1350 0);
DISPLAY 0.978723 (1350 0);
DISPLAY INVISIBLE (1350 0);
FORCEADD QUANTA_TITLE_BLOCK_C..1
(5800 -1400);
FORCEPROP 0 LAST CDS_CON_LAST_MODIFIED Fri Aug 25 14:01:13 2023
J 0
(3915 -1385);
PAINT MONO (3915 -1385);
DISPLAY INVISIBLE (3915 -1385);
FORCEPROP 2 LAST CUSTOM_TXT_CDS <XR_PAGE_TITLE>
J 0
(-2090 3850);
DISPLAY 0.638298 (-2090 3850);
PAINT PINK (-2090 3850);
DISPLAY INVISIBLE (-2090 3850);
FORCEPROP 2 LAST CUSTOM_TXT_CDS <CON_LAST_MODIFIED>
J 0
(3915 -1385);
DISPLAY 0.978723 (3915 -1385);
FORCEPROP 2 LAST CUSTOM_TXT_CDS <CON_PAGE_NUM> OF <CON_TOTAL_PAGES>
J 0
(5354 -1382);
DISPLAY 0.978723 (5354 -1382);
FORCEPROP 2 LAST CUSTOM_TXT_CDS <Q_REV>
J 0
(5616 -1297);
DISPLAY 1.212766 (5616 -1297);
FORCEPROP 2 LAST CUSTOM_TXT_CDS <Q_NUMBER>
J 0
(4397 -1297);
DISPLAY 1.212766 (4397 -1297);
FORCEPROP 2 LAST CUSTOM_TXT_CDS <Q_PROJ>
J 0
(3418 -1298);
DISPLAY 1.212766 (3418 -1298);
FORCEPROP 2 LAST CUSTOM_TXT_CDS <NAME_2>
J 0
(2625 -1350);
FORCEPROP 2 LAST CUSTOM_TXT_CDS <NAME_1>
J 0
(2625 -1225);
FORCEPROP 1 LAST Q_TITLE DDR5 - CPU0 CHG DIMM1(YELLOW)
J 0
(-3566 -1374);
DISPLAY 2.446809 (-3566 -1374);
PAINT GREEN (-3566 -1374);
FORCEPROP 1 LAST Q_DEPT 
J 1
(2037 -1351);
DISPLAY 1.957447 (2037 -1351);
PAINT GREEN (2037 -1351);
FORCEPROP 1 LAST COMMENT_BODY TRUE
J 0
(5812 -1413);
DISPLAY 0.978723 (5812 -1413);
PAINT GREEN (5812 -1413);
DISPLAY INVISIBLE (5812 -1413);
FORCEPROP 2 LAST CDS_XR_PAGE_TITLE CR-94 : @S9S_MB_2U_LIB.S9S_MB_2U(SCH_1):PAGE94
J 0
(-2090 3850);
DISPLAY 0.638298 (-2090 3850);
PAINT PINK (-2090 3850);
DISPLAY INVISIBLE (-2090 3850);
FORCEPROP 2 LAST CDS_LIB pure_quanta
J 0
(5800 -1400);
PAINT MONO (5800 -1400);
DISPLAY INVISIBLE (5800 -1400);
FORCEPROP 1 LAST CDS_LMAN_SYM_OUTLINE -9475,6775,100,-125
J 0
(5800 -1400);
DISPLAY 0.468085 (5800 -1400);
PAINT GREEN (5800 -1400);
DISPLAY INVISIBLE (5800 -1400);
FORCEPROP 2 LAST PAGE_BORDER TRUE
J 0
(-2090 3850);
DISPLAY 0.638298 (-2090 3850);
PAINT PINK (-2090 3850);
DISPLAY INVISIBLE (-2090 3850);
WIRE 17 -1 (-475 4375)(250 4375);
FORCEPROP 2 LAST SIG_NAME M_G_CPU0_SA_DQ<31:0>
J 0
(-410 4385);
DISPLAY 0.680851 (-410 4385);
PAINT WHITE (-410 4385);
WIRE 17 -1 (-3050 2975)(-2225 2975);
FORCEPROP 2 LAST SIG_NAME M_G_CPU0_SA_CB<7:0>
J 0
(-2960 2985);
DISPLAY 0.680851 (-2960 2985);
PAINT WHITE (-2960 2985);
WIRE 17 -1 (-2225 2825)(-2225 2875);
WIRE 17 -1 (-2225 2775)(-2225 2825);
WIRE 17 -1 (-2225 2875)(-2225 2925);
WIRE 17 -1 (-2225 2925)(-2225 2975);
WIRE 17 -1 (-2225 2725)(-2225 2775);
WIRE 17 -1 (-2225 2675)(-2225 2725);
WIRE 17 -1 (-2225 2625)(-2225 2675);
WIRE 17 -1 (-3050 2525)(-2225 2525);
FORCEPROP 2 LAST SIG_NAME M_G_CPU0_SB_CB<7:0>
J 0
(-2960 2535);
DISPLAY 0.680851 (-2960 2535);
PAINT WHITE (-2960 2535);
WIRE 17 -1 (-2225 4075)(-2225 4125);
WIRE 17 -1 (-2225 4125)(-2225 4175);
WIRE 17 -1 (-2225 4175)(-2225 4225);
WIRE 17 -1 (-2225 4225)(-2225 4275);
WIRE 17 -1 (-2225 4275)(-2225 4325);
WIRE 17 -1 (-2225 4325)(-2225 4375);
WIRE 17 -1 (-3050 4375)(-2225 4375);
FORCEPROP 2 LAST SIG_NAME M_G_CPU0_SA_CA<6:0>
J 0
(-2960 4385);
DISPLAY 0.680851 (-2960 4385);
PAINT WHITE (-2960 4385);
WIRE 17 -1 (-2225 3675)(-2225 3725);
WIRE 17 -1 (-2225 3725)(-2225 3775);
WIRE 17 -1 (-2225 3775)(-2225 3825);
WIRE 17 -1 (-2225 3825)(-2225 3875);
WIRE 17 -1 (-2225 3875)(-2225 3925);
WIRE 17 -1 (-2225 3925)(-2225 3975);
WIRE 17 -1 (-3050 3975)(-2225 3975);
FORCEPROP 2 LAST SIG_NAME M_G_CPU0_SB_CA<6:0>
J 0
(-2960 3985);
DISPLAY 0.680851 (-2960 3985);
PAINT WHITE (-2960 3985);
WIRE 17 -1 (-2225 2475)(-2225 2525);
WIRE 17 -1 (-2225 2425)(-2225 2475);
WIRE 17 -1 (-2225 2375)(-2225 2425);
WIRE 17 -1 (-2225 2325)(-2225 2375);
WIRE 17 -1 (-2225 2275)(-2225 2325);
WIRE 17 -1 (-2225 2225)(-2225 2275);
WIRE 17 -1 (-2225 2175)(-2225 2225);
WIRE 17 -1 (-475 4325)(-475 4375);
WIRE 17 -1 (-475 4275)(-475 4325);
WIRE 17 -1 (-475 4225)(-475 4275);
WIRE 17 -1 (-475 4175)(-475 4225);
WIRE 17 -1 (-475 4125)(-475 4175);
WIRE 17 -1 (-475 4075)(-475 4125);
WIRE 17 -1 (-475 4025)(-475 4075);
WIRE 17 -1 (-475 3975)(-475 4025);
WIRE 17 -1 (-475 3925)(-475 3975);
WIRE 17 -1 (-475 3875)(-475 3925);
WIRE 17 -1 (-475 3825)(-475 3875);
WIRE 17 -1 (-475 3775)(-475 3825);
WIRE 17 -1 (-475 3725)(-475 3775);
WIRE 17 -1 (-475 3675)(-475 3725);
WIRE 17 -1 (-475 3625)(-475 3675);
WIRE 17 -1 (-475 3575)(-475 3625);
WIRE 17 -1 (-475 3525)(-475 3575);
WIRE 17 -1 (-475 3475)(-475 3525);
WIRE 17 -1 (-475 3425)(-475 3475);
WIRE 17 -1 (-475 3375)(-475 3425);
WIRE 17 -1 (-475 3325)(-475 3375);
WIRE 17 -1 (-475 3275)(-475 3325);
WIRE 17 -1 (-475 3225)(-475 3275);
WIRE 17 -1 (-475 3175)(-475 3225);
WIRE 17 -1 (-475 3125)(-475 3175);
WIRE 17 -1 (-475 3075)(-475 3125);
WIRE 17 -1 (-475 3025)(-475 3075);
WIRE 17 -1 (-475 2975)(-475 3025);
WIRE 17 -1 (-475 2925)(-475 2975);
WIRE 17 -1 (-475 2875)(-475 2925);
WIRE 17 -1 (-475 2825)(-475 2875);
WIRE 17 -1 (-475 2725)(250 2725);
FORCEPROP 2 LAST SIG_NAME M_G_CPU0_SB_DQ<31:0>
J 0
(-410 2735);
DISPLAY 0.680851 (-410 2735);
PAINT WHITE (-410 2735);
WIRE 17 -1 (-475 2675)(-475 2725);
WIRE 17 -1 (-475 2625)(-475 2675);
WIRE 17 -1 (-475 2575)(-475 2625);
WIRE 17 -1 (-475 2525)(-475 2575);
WIRE 17 -1 (-475 2475)(-475 2525);
WIRE 17 -1 (-475 2425)(-475 2475);
WIRE 17 -1 (-475 2375)(-475 2425);
WIRE 17 -1 (-475 2325)(-475 2375);
WIRE 17 -1 (-475 2275)(-475 2325);
WIRE 17 -1 (-475 2225)(-475 2275);
WIRE 17 -1 (-475 2175)(-475 2225);
WIRE 17 -1 (-475 2125)(-475 2175);
WIRE 17 -1 (-475 2075)(-475 2125);
WIRE 17 -1 (-475 2025)(-475 2075);
WIRE 17 -1 (-475 1975)(-475 2025);
WIRE 17 -1 (-475 1925)(-475 1975);
WIRE 17 -1 (-475 1875)(-475 1925);
WIRE 17 -1 (-475 1825)(-475 1875);
WIRE 17 -1 (-475 1775)(-475 1825);
WIRE 17 -1 (-475 1725)(-475 1775);
WIRE 17 -1 (-475 1675)(-475 1725);
WIRE 17 -1 (-475 1625)(-475 1675);
WIRE 17 -1 (-475 1575)(-475 1625);
WIRE 17 -1 (-475 1525)(-475 1575);
WIRE 17 -1 (-475 1475)(-475 1525);
WIRE 17 -1 (-475 1425)(-475 1475);
WIRE 17 -1 (-475 1375)(-475 1425);
WIRE 17 -1 (-475 1325)(-475 1375);
WIRE 17 -1 (-475 1275)(-475 1325);
WIRE 17 -1 (-475 1225)(-475 1275);
WIRE 17 -1 (-475 1175)(-475 1225);
WIRE 17 -1 (2275 2525)(2275 2625);
WIRE 17 -1 (2275 2425)(2275 2525);
WIRE 17 -1 (2275 2625)(2275 2725);
WIRE 17 -1 (2275 2825)(2275 2725);
WIRE 17 -1 (2275 2825)(2275 2925);
WIRE 17 -1 (2275 2925)(2275 3025);
WIRE 17 -1 (2275 3025)(2275 3125);
WIRE 17 -1 (2275 3125)(2275 3225);
WIRE 17 -1 (2275 3225)(2275 3325);
WIRE 17 -1 (2275 3325)(3300 3325);
FORCEPROP 2 LAST SIG_NAME M_G_CPU0_SB_DQS_DP<9:0>
J 0
(2515 3335);
DISPLAY 0.680851 (2515 3335);
PAINT WHITE (2515 3335);
WIRE 17 -1 (2275 3575)(2275 3675);
WIRE 17 -1 (2275 3475)(2275 3575);
WIRE 17 -1 (2275 3675)(2275 3775);
WIRE 17 -1 (2275 3875)(2275 3775);
WIRE 17 -1 (2275 3875)(2275 3975);
WIRE 17 -1 (2275 3975)(2275 4075);
WIRE 17 -1 (2275 4075)(2275 4175);
WIRE 17 -1 (2275 4175)(2275 4275);
WIRE 17 -1 (2275 4275)(2275 4375);
WIRE 17 -1 (2275 4375)(3300 4375);
FORCEPROP 2 LAST SIG_NAME M_G_CPU0_SA_DQS_DP<9:0>
J 0
(2515 4385);
DISPLAY 0.680851 (2515 4385);
PAINT WHITE (2515 4385);
WIRE 17 -1 (2450 2475)(2450 2575);
WIRE 17 -1 (2450 2375)(2450 2475);
WIRE 17 -1 (2450 2575)(2450 2675);
WIRE 17 -1 (2450 2775)(2450 2675);
WIRE 17 -1 (2450 2775)(2450 2875);
WIRE 17 -1 (2450 2875)(2450 2975);
WIRE 17 -1 (2450 2975)(2450 3075);
WIRE 17 -1 (2450 3075)(2450 3175);
WIRE 17 -1 (2450 3175)(2450 3275);
WIRE 17 -1 (2450 3275)(3300 3275);
FORCEPROP 2 LAST SIG_NAME M_G_CPU0_SB_DQS_DN<9:0>
J 0
(2515 3285);
DISPLAY 0.680851 (2515 3285);
PAINT WHITE (2515 3285);
WIRE 17 -1 (2450 3425)(2450 3525);
WIRE 17 -1 (2450 3525)(2450 3625);
WIRE 17 -1 (2450 3625)(2450 3725);
WIRE 17 -1 (2450 3825)(2450 3725);
WIRE 17 -1 (2450 3825)(2450 3925);
WIRE 17 -1 (2450 3925)(2450 4025);
WIRE 17 -1 (2450 4025)(2450 4125);
WIRE 17 -1 (2450 4125)(2450 4225);
WIRE 17 -1 (2450 4225)(2450 4325);
WIRE 17 -1 (2450 4325)(3300 4325);
FORCEPROP 2 LAST SIG_NAME M_G_CPU0_SA_DQS_DN<9:0>
J 0
(2515 4335);
DISPLAY 0.680851 (2515 4335);
PAINT WHITE (2515 4335);
WIRE 16 -1 (-3000 2175)(-3000 1900);
WIRE 16 -1 (2200 750)(2200 700);
WIRE 16 -1 (3900 4850)(3900 4350);
WIRE 16 -1 (1200 575)(1200 750);
WIRE 16 -1 (-1950 25)(-1950 100);
WIRE 16 -1 (5600 1000)(5600 700);
WIRE 16 -1 (5600 1050)(5600 1000);
WIRE 16 -1 (5350 1000)(5600 1000);
WIRE 16 -1 (3900 700)(3900 1100);
WIRE 16 -1 (2825 150)(2825 225);
WIRE 16 -1 (1200 375)(1200 150);
WIRE 16 -1 (-3000 1900)(-1950 1900);
WIRE 16 -1 (-1950 1850)(-2950 1850);
FORCEPROP 2 LAST SIG_NAME PD_CHG_CPU0_DIMM1_SAA
J 0
(-2960 1860);
DISPLAY 0.680851 (-2960 1860);
PAINT WHITE (-2960 1860);
WIRE 16 -1 (-1950 1800)(-2950 1800);
FORCEPROP 2 LAST SIG_NAME I3C_SPD_DDREFGH_CPU0_LVC1_SDA
J 0
(-2960 1810);
DISPLAY 0.680851 (-2960 1810);
PAINT WHITE (-2960 1810);
WIRE 16 -1 (-3450 1650)(-3250 1650);
WIRE 16 -1 (-3450 1750)(-3450 1650);
WIRE 16 -1 (-1950 1750)(-3450 1750);
FORCEPROP 2 LAST SIG_NAME I3C_SPD_DDREFGH_CPU0_LVC1_SCL_R5
J 0
(-3010 1760);
DISPLAY 0.680851 (-3010 1760);
PAINT WHITE (-3010 1760);
WIRE 16 -1 (-1950 2000)(-3050 2000);
FORCEPROP 2 LAST SIG_NAME M_G_CPU0_ALERT_N
J 0
(-2962 2009);
DISPLAY 0.680851 (-2962 2009);
PAINT WHITE (-2962 2009);
WIRE 16 -1 (-2325 2100)(-3050 2100);
FORCEPROP 2 LAST SIG_NAME RST_M_GH_CPU0_FPGA_N
J 0
(-2962 2109);
DISPLAY 0.680851 (-2962 2109);
PAINT WHITE (-2962 2109);
WIRE 16 -1 (-2325 2100)(-2325 2050);
WIRE 16 -1 (-2325 2050)(-1950 2050);
WIRE 16 -1 (-1875 1600)(-1900 1600);
WIRE 16 -1 (-1875 1650)(-3050 1650);
FORCEPROP 2 LAST SIG_NAME I3C_SPD_DDREFGH_CPU0_LVC1_SCL
J 0
(-2835 1660);
DISPLAY 0.680851 (-2835 1660);
PAINT WHITE (-2835 1660);
WIRE 16 -1 (-1875 1650)(-1875 1600);
WIRE 16 -1 (-2125 2150)(-1950 2150);
WIRE 16 -1 (-1950 3400)(-3050 3400);
FORCEPROP 2 LAST SIG_NAME M_G_CPU0_SA_CS_N<1>
J 0
(-2962 3409);
DISPLAY 0.680851 (-2962 3409);
PAINT WHITE (-2962 3409);
WIRE 16 -1 (2075 2600)(2175 2600);
WIRE 16 -1 (2075 2550)(2350 2550);
WIRE 16 -1 (2075 4100)(2350 4100);
WIRE 16 -1 (2075 4200)(2350 4200);
WIRE 16 -1 (2075 4300)(2350 4300);
WIRE 16 -1 (2075 3900)(2350 3900);
WIRE 16 -1 (2075 4000)(2350 4000);
WIRE 16 -1 (2075 3800)(2350 3800);
WIRE 16 -1 (2075 3700)(2350 3700);
WIRE 16 -1 (2075 3600)(2350 3600);
WIRE 16 -1 (2075 3500)(2350 3500);
WIRE 16 -1 (2075 3400)(2350 3400);
WIRE 16 -1 (2075 3150)(2350 3150);
WIRE 16 -1 (2075 3250)(2350 3250);
WIRE 16 -1 (2075 2950)(2350 2950);
WIRE 16 -1 (2075 3050)(2350 3050);
WIRE 16 -1 (2075 2850)(2350 2850);
WIRE 16 -1 (2075 2650)(2350 2650);
WIRE 16 -1 (2075 2750)(2350 2750);
WIRE 16 -1 (2075 2350)(2350 2350);
WIRE 16 -1 (2075 2450)(2350 2450);
WIRE 16 -1 (2075 4350)(2175 4350);
WIRE 16 -1 (2075 4150)(2175 4150);
WIRE 16 -1 (2075 4250)(2175 4250);
WIRE 16 -1 (2075 3850)(2175 3850);
WIRE 16 -1 (2075 3950)(2175 3950);
WIRE 16 -1 (2075 4050)(2175 4050);
WIRE 16 -1 (2075 3650)(2175 3650);
WIRE 16 -1 (2075 3750)(2175 3750);
WIRE 16 -1 (2075 3450)(2175 3450);
WIRE 16 -1 (2075 3550)(2175 3550);
WIRE 16 -1 (2075 3100)(2175 3100);
WIRE 16 -1 (2075 3200)(2175 3200);
WIRE 16 -1 (2075 3300)(2175 3300);
WIRE 16 -1 (2075 3000)(2175 3000);
WIRE 16 -1 (2075 2900)(2175 2900);
WIRE 16 -1 (2075 2800)(2175 2800);
WIRE 16 -1 (2075 2700)(2175 2700);
WIRE 16 -1 (2075 2400)(2175 2400);
WIRE 16 -1 (2075 2500)(2175 2500);
WIRE 16 -1 (4150 4350)(3900 4350);
WIRE 16 -1 (3900 4350)(3900 4300);
WIRE 16 -1 (3900 4300)(4150 4300);
WIRE 16 -1 (3900 4300)(3900 4250);
WIRE 16 -1 (4150 4250)(3900 4250);
WIRE 16 -1 (3900 1100)(4150 1100);
WIRE 16 -1 (3900 1100)(3900 1150);
WIRE 16 -1 (3900 1150)(4150 1150);
WIRE 16 -1 (3900 1150)(3900 1200);
WIRE 16 -1 (3900 1200)(4150 1200);
WIRE 16 -1 (3900 1200)(3900 1250);
WIRE 16 -1 (3900 1250)(4150 1250);
WIRE 16 -1 (3900 1250)(3900 1300);
WIRE 16 -1 (3900 1300)(4150 1300);
WIRE 16 -1 (3900 1300)(3900 1350);
WIRE 16 -1 (3900 1350)(4150 1350);
WIRE 16 -1 (3900 1350)(3900 1400);
WIRE 16 -1 (3900 1400)(4150 1400);
WIRE 16 -1 (3900 1400)(3900 1450);
WIRE 16 -1 (3900 1450)(4150 1450);
WIRE 16 -1 (3900 1450)(3900 1500);
WIRE 16 -1 (3900 1500)(4150 1500);
WIRE 16 -1 (3900 1500)(3900 1550);
WIRE 16 -1 (3900 1550)(4150 1550);
WIRE 16 -1 (3900 1550)(3900 1600);
WIRE 16 -1 (4150 1600)(3900 1600);
WIRE 16 -1 (3900 1600)(3900 1650);
WIRE 16 -1 (3900 1650)(4150 1650);
WIRE 16 -1 (3900 1650)(3900 1700);
WIRE 16 -1 (3900 1700)(4150 1700);
WIRE 16 -1 (3900 1700)(3900 1750);
WIRE 16 -1 (3900 1750)(4150 1750);
WIRE 16 -1 (3900 1750)(3900 1800);
WIRE 16 -1 (3900 1800)(4150 1800);
WIRE 16 -1 (3900 1800)(3900 1850);
WIRE 16 -1 (3900 1850)(4150 1850);
WIRE 16 -1 (3900 1850)(3900 1900);
WIRE 16 -1 (3900 1900)(4150 1900);
WIRE 16 -1 (3900 1900)(3900 1950);
WIRE 16 -1 (3900 1950)(4150 1950);
WIRE 16 -1 (3900 1950)(3900 2000);
WIRE 16 -1 (3900 2000)(4150 2000);
WIRE 16 -1 (3900 2000)(3900 2050);
WIRE 16 -1 (3900 2050)(4150 2050);
WIRE 16 -1 (3900 2050)(3900 2100);
WIRE 16 -1 (4150 2100)(3900 2100);
WIRE 16 -1 (3900 2100)(3900 2150);
WIRE 16 -1 (3900 2150)(4150 2150);
WIRE 16 -1 (3900 2150)(3900 2200);
WIRE 16 -1 (3900 2200)(4150 2200);
WIRE 16 -1 (3900 2200)(3900 2250);
WIRE 16 -1 (3900 2250)(4150 2250);
WIRE 16 -1 (3900 2250)(3900 2300);
WIRE 16 -1 (3900 2300)(4150 2300);
WIRE 16 -1 (3900 2300)(3900 2350);
WIRE 16 -1 (3900 2350)(4150 2350);
WIRE 16 -1 (3900 2350)(3900 2400);
WIRE 16 -1 (3900 2400)(4150 2400);
WIRE 16 -1 (3900 2400)(3900 2450);
WIRE 16 -1 (3900 2450)(4150 2450);
WIRE 16 -1 (3900 2450)(3900 2500);
WIRE 16 -1 (3900 2500)(4150 2500);
WIRE 16 -1 (3900 2500)(3900 2550);
WIRE 16 -1 (3900 2550)(4150 2550);
WIRE 16 -1 (3900 2550)(3900 2600);
WIRE 16 -1 (4150 2600)(3900 2600);
WIRE 16 -1 (3900 2600)(3900 2650);
WIRE 16 -1 (3900 2650)(4150 2650);
WIRE 16 -1 (3900 2650)(3900 2700);
WIRE 16 -1 (3900 2700)(4150 2700);
WIRE 16 -1 (3900 2700)(3900 2750);
WIRE 16 -1 (3900 2750)(4150 2750);
WIRE 16 -1 (3900 2750)(3900 2800);
WIRE 16 -1 (3900 2800)(4150 2800);
WIRE 16 -1 (3900 2800)(3900 2850);
WIRE 16 -1 (3900 2850)(4150 2850);
WIRE 16 -1 (3900 2850)(3900 2900);
WIRE 16 -1 (3900 2900)(4150 2900);
WIRE 16 -1 (3900 2900)(3900 2950);
WIRE 16 -1 (3900 2950)(4150 2950);
WIRE 16 -1 (3900 2950)(3900 3000);
WIRE 16 -1 (3900 3000)(4150 3000);
WIRE 16 -1 (3900 3000)(3900 3050);
WIRE 16 -1 (3900 3050)(4150 3050);
WIRE 16 -1 (3900 3050)(3900 3100);
WIRE 16 -1 (4150 3100)(3900 3100);
WIRE 16 -1 (3900 3100)(3900 3150);
WIRE 16 -1 (3900 3150)(4150 3150);
WIRE 16 -1 (3900 3150)(3900 3200);
WIRE 16 -1 (3900 3200)(4150 3200);
WIRE 16 -1 (3900 3200)(3900 3250);
WIRE 16 -1 (3900 3250)(4150 3250);
WIRE 16 -1 (3900 3250)(3900 3300);
WIRE 16 -1 (3900 3300)(4150 3300);
WIRE 16 -1 (3900 3300)(3900 3350);
WIRE 16 -1 (3900 3350)(4150 3350);
WIRE 16 -1 (3900 3350)(3900 3400);
WIRE 16 -1 (3900 3400)(4150 3400);
WIRE 16 -1 (3900 3400)(3900 3450);
WIRE 16 -1 (3900 3450)(4150 3450);
WIRE 16 -1 (3900 3450)(3900 3500);
WIRE 16 -1 (3900 3500)(4150 3500);
WIRE 16 -1 (3900 3500)(3900 3550);
WIRE 16 -1 (3900 3550)(4150 3550);
WIRE 16 -1 (3900 3550)(3900 3600);
WIRE 16 -1 (4150 3600)(3900 3600);
WIRE 16 -1 (3900 3600)(3900 3650);
WIRE 16 -1 (3900 3650)(4150 3650);
WIRE 16 -1 (3900 3650)(3900 3700);
WIRE 16 -1 (3900 3700)(4150 3700);
WIRE 16 -1 (3900 3700)(3900 3750);
WIRE 16 -1 (3900 3750)(4150 3750);
WIRE 16 -1 (3900 3750)(3900 3800);
WIRE 16 -1 (3900 3800)(4150 3800);
WIRE 16 -1 (3900 3800)(3900 3850);
WIRE 16 -1 (3900 3850)(4150 3850);
WIRE 16 -1 (3900 3850)(3900 3900);
WIRE 16 -1 (3900 3900)(4150 3900);
WIRE 16 -1 (3900 3900)(3900 3950);
WIRE 16 -1 (3900 3950)(4150 3950);
WIRE 16 -1 (3900 3950)(3900 4000);
WIRE 16 -1 (3900 4000)(4150 4000);
WIRE 16 -1 (3900 4000)(3900 4050);
WIRE 16 -1 (3900 4050)(4150 4050);
WIRE 16 -1 (3900 4050)(3900 4100);
WIRE 16 -1 (4150 4100)(3900 4100);
WIRE 16 -1 (3900 4100)(3900 4150);
WIRE 16 -1 (3900 4150)(4150 4150);
WIRE 16 -1 (3900 4150)(3900 4200);
WIRE 16 -1 (4150 4200)(3900 4200);
WIRE 16 -1 (-750 2550)(-575 2550);
WIRE 16 -1 (-1950 1400)(-3050 1400);
FORCEPROP 2 LAST SIG_NAME TP_CHG_CPU0_DIMM1_FRU_6
J 0
(-2962 1409);
DISPLAY 0.680851 (-2962 1409);
PAINT WHITE (-2962 1409);
WIRE 16 -1 (-1950 1100)(-3050 1100);
FORCEPROP 2 LAST SIG_NAME TP_CHG_CPU0_DIMM1_FRU_0
J 0
(-2962 1109);
DISPLAY 0.680851 (-2962 1109);
PAINT WHITE (-2962 1109);
WIRE 16 -1 (-1950 1150)(-3050 1150);
FORCEPROP 2 LAST SIG_NAME TP_CHG_CPU0_DIMM1_FRU_1
J 0
(-2962 1159);
DISPLAY 0.680851 (-2962 1159);
PAINT WHITE (-2962 1159);
WIRE 16 -1 (-1950 1200)(-3050 1200);
FORCEPROP 2 LAST SIG_NAME TP_CHG_CPU0_DIMM1_FRU_2
J 0
(-2962 1209);
DISPLAY 0.680851 (-2962 1209);
PAINT WHITE (-2962 1209);
WIRE 16 -1 (-1950 1250)(-3050 1250);
FORCEPROP 2 LAST SIG_NAME TP_CHG_CPU0_DIMM1_FRU_3
J 0
(-2962 1259);
DISPLAY 0.680851 (-2962 1259);
PAINT WHITE (-2962 1259);
WIRE 16 -1 (-1950 1300)(-3050 1300);
FORCEPROP 2 LAST SIG_NAME TP_CHG_CPU0_DIMM1_FRU_4
J 0
(-2962 1309);
DISPLAY 0.680851 (-2962 1309);
PAINT WHITE (-2962 1309);
WIRE 16 -1 (-1950 1350)(-3050 1350);
FORCEPROP 2 LAST SIG_NAME TP_CHG_CPU0_DIMM1_FRU_5
J 0
(-2962 1359);
DISPLAY 0.680851 (-2962 1359);
PAINT WHITE (-2962 1359);
WIRE 16 -1 (-1950 1500)(-3050 1500);
FORCEPROP 2 LAST SIG_NAME PWRGD_CHG_CPU0_DIMM1
J 0
(-2962 1509);
DISPLAY 0.680851 (-2962 1509);
PAINT WHITE (-2962 1509);
WIRE 16 -1 (-1950 3500)(-3050 3500);
FORCEPROP 2 LAST SIG_NAME M_G_CPU0_SB_PAR
J 0
(-2962 3509);
DISPLAY 0.680851 (-2962 3509);
PAINT WHITE (-2962 3509);
WIRE 16 -1 (-1950 3550)(-3050 3550);
FORCEPROP 2 LAST SIG_NAME M_G_CPU0_SA_PAR
J 0
(-2962 3559);
DISPLAY 0.680851 (-2962 3559);
PAINT WHITE (-2962 3559);
WIRE 16 -1 (-1950 900)(-3050 900);
FORCEPROP 2 LAST SIG_NAME M_G_CPU0_SB_RSP<0>
J 0
(-2962 909);
DISPLAY 0.680851 (-2962 909);
PAINT WHITE (-2962 909);
WIRE 16 -1 (-1950 950)(-3050 950);
FORCEPROP 2 LAST SIG_NAME M_G_CPU0_SA_RSP<0>
J 0
(-2962 959);
DISPLAY 0.680851 (-2962 959);
PAINT WHITE (-2962 959);
WIRE 16 -1 (-750 1150)(-575 1150);
WIRE 16 -1 (-750 1200)(-575 1200);
WIRE 16 -1 (-750 1250)(-575 1250);
WIRE 16 -1 (-750 1300)(-575 1300);
WIRE 16 -1 (-750 1350)(-575 1350);
WIRE 16 -1 (-750 1400)(-575 1400);
WIRE 16 -1 (-750 1450)(-575 1450);
WIRE 16 -1 (-750 1500)(-575 1500);
WIRE 16 -1 (-750 1550)(-575 1550);
WIRE 16 -1 (-750 1600)(-575 1600);
WIRE 16 -1 (-750 1650)(-575 1650);
WIRE 16 -1 (-750 1700)(-575 1700);
WIRE 16 -1 (-750 1750)(-575 1750);
WIRE 16 -1 (-750 1800)(-575 1800);
WIRE 16 -1 (-750 1850)(-575 1850);
WIRE 16 -1 (-750 1900)(-575 1900);
WIRE 16 -1 (-750 1950)(-575 1950);
WIRE 16 -1 (-750 2000)(-575 2000);
WIRE 16 -1 (-750 2050)(-575 2050);
WIRE 16 -1 (-750 2100)(-575 2100);
WIRE 16 -1 (-750 2150)(-575 2150);
WIRE 16 -1 (-750 2200)(-575 2200);
WIRE 16 -1 (-750 2250)(-575 2250);
WIRE 16 -1 (-750 2300)(-575 2300);
WIRE 16 -1 (-750 2350)(-575 2350);
WIRE 16 -1 (-750 2400)(-575 2400);
WIRE 16 -1 (-750 2450)(-575 2450);
WIRE 16 -1 (-750 2500)(-575 2500);
WIRE 16 -1 (-750 2600)(-575 2600);
WIRE 16 -1 (-750 2650)(-575 2650);
WIRE 16 -1 (-750 2700)(-575 2700);
WIRE 16 -1 (-750 2800)(-575 2800);
WIRE 16 -1 (-750 2850)(-575 2850);
WIRE 16 -1 (-750 2900)(-575 2900);
WIRE 16 -1 (-750 2950)(-575 2950);
WIRE 16 -1 (-750 3000)(-575 3000);
WIRE 16 -1 (-750 3050)(-575 3050);
WIRE 16 -1 (-750 3100)(-575 3100);
WIRE 16 -1 (-750 3150)(-575 3150);
WIRE 16 -1 (-750 3200)(-575 3200);
WIRE 16 -1 (-750 3250)(-575 3250);
WIRE 16 -1 (-750 3300)(-575 3300);
WIRE 16 -1 (-750 3350)(-575 3350);
WIRE 16 -1 (-750 3400)(-575 3400);
WIRE 16 -1 (-750 3450)(-575 3450);
WIRE 16 -1 (-750 3500)(-575 3500);
WIRE 16 -1 (-750 3550)(-575 3550);
WIRE 16 -1 (-750 3600)(-575 3600);
WIRE 16 -1 (-750 3650)(-575 3650);
WIRE 16 -1 (-750 3700)(-575 3700);
WIRE 16 -1 (-750 3750)(-575 3750);
WIRE 16 -1 (-750 3800)(-575 3800);
WIRE 16 -1 (-750 3850)(-575 3850);
WIRE 16 -1 (-750 3900)(-575 3900);
WIRE 16 -1 (-750 3950)(-575 3950);
WIRE 16 -1 (-750 4000)(-575 4000);
WIRE 16 -1 (-750 4050)(-575 4050);
WIRE 16 -1 (-750 4100)(-575 4100);
WIRE 16 -1 (-750 4150)(-575 4150);
WIRE 16 -1 (-750 4200)(-575 4200);
WIRE 16 -1 (-750 4250)(-575 4250);
WIRE 16 -1 (-750 4300)(-575 4300);
WIRE 16 -1 (-1950 3250)(-3050 3250);
FORCEPROP 2 LAST SIG_NAME M_G_CPU0_SB_CS_N<1>
J 0
(-2962 3259);
DISPLAY 0.680851 (-2962 3259);
PAINT WHITE (-2962 3259);
WIRE 16 -1 (-1950 3200)(-3050 3200);
FORCEPROP 2 LAST SIG_NAME M_G_CPU0_SB_CS_N<0>
J 0
(-2962 3209);
DISPLAY 0.680851 (-2962 3209);
PAINT WHITE (-2962 3209);
WIRE 16 -1 (-1950 3350)(-3050 3350);
FORCEPROP 2 LAST SIG_NAME M_G_CPU0_SA_CS_N<0>
J 0
(-2962 3359);
DISPLAY 0.680851 (-2962 3359);
PAINT WHITE (-2962 3359);
WIRE 16 -1 (-1950 3100)(-3050 3100);
FORCEPROP 2 LAST SIG_NAME M_G_CPU0_CLK_DP<0>
J 0
(-2962 3109);
DISPLAY 0.680851 (-2962 3109);
PAINT WHITE (-2962 3109);
WIRE 16 -1 (-1950 3050)(-3050 3050);
FORCEPROP 2 LAST SIG_NAME M_G_CPU0_CLK_DN<0>
J 0
(-2962 3059);
DISPLAY 0.680851 (-2962 3059);
PAINT WHITE (-2962 3059);
WIRE 16 -1 (-2125 2200)(-1950 2200);
WIRE 16 -1 (-2125 2250)(-1950 2250);
WIRE 16 -1 (-2125 2300)(-1950 2300);
WIRE 16 -1 (-2125 2350)(-1950 2350);
WIRE 16 -1 (-2125 2400)(-1950 2400);
WIRE 16 -1 (-2125 2450)(-1950 2450);
WIRE 16 -1 (-2125 2600)(-1950 2600);
WIRE 16 -1 (-2125 2700)(-1950 2700);
WIRE 16 -1 (-2125 2750)(-1950 2750);
WIRE 16 -1 (-2125 2850)(-1950 2850);
WIRE 16 -1 (-2125 2900)(-1950 2900);
WIRE 16 -1 (-2125 3950)(-1950 3950);
WIRE 16 -1 (-2125 4350)(-1950 4350);
WIRE 16 -1 (-2125 3900)(-1950 3900);
WIRE 16 -1 (-2125 4300)(-1950 4300);
WIRE 16 -1 (-2125 3850)(-1950 3850);
WIRE 16 -1 (-2125 4250)(-1950 4250);
WIRE 16 -1 (-2125 3800)(-1950 3800);
WIRE 16 -1 (-2125 4200)(-1950 4200);
WIRE 16 -1 (-2125 3750)(-1950 3750);
WIRE 16 -1 (-2125 4150)(-1950 4150);
WIRE 16 -1 (-2125 3700)(-1950 3700);
WIRE 16 -1 (-2125 4100)(-1950 4100);
WIRE 16 -1 (-2125 3650)(-1950 3650);
WIRE 16 -1 (-2125 4050)(-1950 4050);
WIRE 16 -1 (-2125 2500)(-1950 2500);
WIRE 16 -1 (-2125 2650)(-1950 2650);
WIRE 16 -1 (-2125 2800)(-1950 2800);
WIRE 16 -1 (-2125 2950)(-1950 2950);
WIRE 16 -1 (-750 4350)(-575 4350);
WIRE 16 3135 (850 975)(850 -325);
WIRE 16 3135 (3450 975)(850 975);
WIRE 16 3135 (850 -325)(3450 -325);
WIRE 16 3135 (3450 -325)(3450 975);
WIRE 16 -1 (2200 700)(2200 575);
WIRE 16 -1 (2825 700)(2200 700);
WIRE 16 -1 (2825 575)(2825 700);
WIRE 16 -1 (5350 4350)(5600 4350);
WIRE 16 -1 (5350 4300)(5600 4300);
WIRE 16 -1 (5600 4350)(5600 4300);
WIRE 16 -1 (5350 4250)(5600 4250);
WIRE 16 -1 (5600 4300)(5600 4250);
WIRE 16 -1 (5350 4200)(5600 4200);
WIRE 16 -1 (5600 4250)(5600 4200);
WIRE 16 -1 (5350 4150)(5600 4150);
WIRE 16 -1 (5600 4200)(5600 4150);
WIRE 16 -1 (5350 4100)(5600 4100);
WIRE 16 -1 (5600 4150)(5600 4100);
WIRE 16 -1 (5350 4050)(5600 4050);
WIRE 16 -1 (5600 4100)(5600 4050);
WIRE 16 -1 (5350 4000)(5600 4000);
WIRE 16 -1 (5600 4050)(5600 4000);
WIRE 16 -1 (5350 3950)(5600 3950);
WIRE 16 -1 (5600 4000)(5600 3950);
WIRE 16 -1 (5350 3900)(5600 3900);
WIRE 16 -1 (5600 3950)(5600 3900);
WIRE 16 -1 (5350 3850)(5600 3850);
WIRE 16 -1 (5600 3900)(5600 3850);
WIRE 16 -1 (5350 3800)(5600 3800);
WIRE 16 -1 (5600 3850)(5600 3800);
WIRE 16 -1 (5350 3750)(5600 3750);
WIRE 16 -1 (5600 3800)(5600 3750);
WIRE 16 -1 (5350 3700)(5600 3700);
WIRE 16 -1 (5600 3750)(5600 3700);
WIRE 16 -1 (5350 3650)(5600 3650);
WIRE 16 -1 (5600 3700)(5600 3650);
WIRE 16 -1 (5350 3600)(5600 3600);
WIRE 16 -1 (5600 3600)(5600 3650);
WIRE 16 -1 (5350 3550)(5600 3550);
WIRE 16 -1 (5600 3600)(5600 3550);
WIRE 16 -1 (5600 3500)(5350 3500);
WIRE 16 -1 (5600 3550)(5600 3500);
WIRE 16 -1 (5600 3450)(5350 3450);
WIRE 16 -1 (5600 3500)(5600 3450);
WIRE 16 -1 (5350 3400)(5600 3400);
WIRE 16 -1 (5600 3450)(5600 3400);
WIRE 16 -1 (5350 3350)(5600 3350);
WIRE 16 -1 (5600 3400)(5600 3350);
WIRE 16 -1 (5350 3300)(5600 3300);
WIRE 16 -1 (5600 3350)(5600 3300);
WIRE 16 -1 (5350 3250)(5600 3250);
WIRE 16 -1 (5600 3300)(5600 3250);
WIRE 16 -1 (5350 3200)(5600 3200);
WIRE 16 -1 (5600 3250)(5600 3200);
WIRE 16 -1 (5350 3150)(5600 3150);
WIRE 16 -1 (5600 3200)(5600 3150);
WIRE 16 -1 (5350 3100)(5600 3100);
WIRE 16 -1 (5600 3100)(5600 3150);
WIRE 16 -1 (5350 3050)(5600 3050);
WIRE 16 -1 (5600 3100)(5600 3050);
WIRE 16 -1 (5600 3000)(5350 3000);
WIRE 16 -1 (5600 3050)(5600 3000);
WIRE 16 -1 (5600 2950)(5350 2950);
WIRE 16 -1 (5600 3000)(5600 2950);
WIRE 16 -1 (5350 2900)(5600 2900);
WIRE 16 -1 (5600 2950)(5600 2900);
WIRE 16 -1 (5350 2850)(5600 2850);
WIRE 16 -1 (5600 2900)(5600 2850);
WIRE 16 -1 (5350 2800)(5600 2800);
WIRE 16 -1 (5600 2850)(5600 2800);
WIRE 16 -1 (5350 2750)(5600 2750);
WIRE 16 -1 (5600 2800)(5600 2750);
WIRE 16 -1 (5350 2700)(5600 2700);
WIRE 16 -1 (5600 2750)(5600 2700);
WIRE 16 -1 (5350 2650)(5600 2650);
WIRE 16 -1 (5600 2700)(5600 2650);
WIRE 16 -1 (5350 2600)(5600 2600);
WIRE 16 -1 (5600 2600)(5600 2650);
WIRE 16 -1 (5350 2550)(5600 2550);
WIRE 16 -1 (5600 2600)(5600 2550);
WIRE 16 -1 (5600 2500)(5350 2500);
WIRE 16 -1 (5600 2550)(5600 2500);
WIRE 16 -1 (5600 2450)(5350 2450);
WIRE 16 -1 (5600 2500)(5600 2450);
WIRE 16 -1 (5350 2400)(5600 2400);
WIRE 16 -1 (5600 2450)(5600 2400);
WIRE 16 -1 (5350 2350)(5600 2350);
WIRE 16 -1 (5600 2400)(5600 2350);
WIRE 16 -1 (5350 2300)(5600 2300);
WIRE 16 -1 (5600 2350)(5600 2300);
WIRE 16 -1 (5350 2250)(5600 2250);
WIRE 16 -1 (5600 2300)(5600 2250);
WIRE 16 -1 (5350 2200)(5600 2200);
WIRE 16 -1 (5600 2250)(5600 2200);
WIRE 16 -1 (5350 2150)(5600 2150);
WIRE 16 -1 (5600 2200)(5600 2150);
WIRE 16 -1 (5350 2100)(5600 2100);
WIRE 16 -1 (5600 2100)(5600 2150);
WIRE 16 -1 (5350 2050)(5600 2050);
WIRE 16 -1 (5600 2100)(5600 2050);
WIRE 16 -1 (5600 2000)(5350 2000);
WIRE 16 -1 (5600 2050)(5600 2000);
WIRE 16 -1 (5600 1950)(5350 1950);
WIRE 16 -1 (5600 2000)(5600 1950);
WIRE 16 -1 (5600 1900)(5350 1900);
WIRE 16 -1 (5600 1950)(5600 1900);
WIRE 16 -1 (5600 1850)(5350 1850);
WIRE 16 -1 (5600 1900)(5600 1850);
WIRE 16 -1 (5350 1800)(5600 1800);
WIRE 16 -1 (5600 1800)(5600 1850);
WIRE 16 -1 (5600 1750)(5350 1750);
WIRE 16 -1 (5600 1750)(5600 1800);
WIRE 16 -1 (5600 1700)(5350 1700);
WIRE 16 -1 (5600 1750)(5600 1700);
WIRE 16 -1 (5600 1650)(5350 1650);
WIRE 16 -1 (5600 1700)(5600 1650);
WIRE 16 -1 (5350 1600)(5600 1600);
WIRE 16 -1 (5600 1650)(5600 1600);
WIRE 16 -1 (5350 1550)(5600 1550);
WIRE 16 -1 (5600 1600)(5600 1550);
WIRE 16 -1 (5350 1500)(5600 1500);
WIRE 16 -1 (5600 1550)(5600 1500);
WIRE 16 -1 (5350 1450)(5600 1450);
WIRE 16 -1 (5600 1500)(5600 1450);
WIRE 16 -1 (5350 1400)(5600 1400);
WIRE 16 -1 (5600 1450)(5600 1400);
WIRE 16 -1 (5350 1350)(5600 1350);
WIRE 16 -1 (5600 1400)(5600 1350);
WIRE 16 -1 (5350 1300)(5600 1300);
WIRE 16 -1 (5600 1350)(5600 1300);
WIRE 16 -1 (5350 1250)(5600 1250);
WIRE 16 -1 (5600 1250)(5600 1300);
WIRE 16 -1 (5350 1200)(5600 1200);
WIRE 16 -1 (5600 1250)(5600 1200);
WIRE 16 -1 (5350 1100)(5600 1100);
WIRE 16 -1 (5600 1200)(5600 1100);
WIRE 16 -1 (5600 1100)(5600 1050);
WIRE 16 -1 (5350 1050)(5600 1050);
WIRE 16 -1 (-1950 400)(-3050 400);
FORCEPROP 2 LAST SIG_NAME PD_CHG_CPU0_DIMM1_SAA
J 0
(-2962 409);
DISPLAY 0.680851 (-2962 409);
PAINT WHITE (-2962 409);
WIRE 16 -1 (-1950 300)(-1950 400);
WIRE 16 -1 (2200 225)(2200 375);
WIRE 16 -1 (2825 225)(2200 225);
WIRE 16 -1 (2825 225)(2825 375);
DOT 1 (5600 1000);
DOT 1 (5600 1050);
DOT 1 (5600 1100);
DOT 1 (5600 4300);
DOT 1 (5600 4250);
DOT 1 (5600 4150);
DOT 1 (5600 4200);
DOT 1 (5600 4100);
DOT 1 (5600 4050);
DOT 1 (5600 4000);
DOT 1 (5600 3950);
DOT 1 (5600 3900);
DOT 1 (5600 3850);
DOT 1 (5600 3800);
DOT 1 (5600 3750);
DOT 1 (5600 3700);
DOT 1 (5600 3600);
DOT 1 (5600 3650);
DOT 1 (5600 3550);
DOT 1 (5600 3500);
DOT 1 (5600 3450);
DOT 1 (5600 3400);
DOT 1 (5600 3350);
DOT 1 (5600 3300);
DOT 1 (5600 3250);
DOT 1 (5600 3200);
DOT 1 (5600 3150);
DOT 1 (5600 3100);
DOT 1 (5600 3050);
DOT 1 (5600 3000);
DOT 1 (5600 2950);
DOT 1 (5600 2900);
DOT 1 (5600 2850);
DOT 1 (5600 2800);
DOT 1 (5600 2750);
DOT 1 (5600 2700);
DOT 1 (5600 2600);
DOT 1 (5600 2650);
DOT 1 (5600 2550);
DOT 1 (5600 2500);
DOT 1 (5600 2450);
DOT 1 (5600 2400);
DOT 1 (5600 2350);
DOT 1 (5600 2300);
DOT 1 (5600 2250);
DOT 1 (5600 2200);
DOT 1 (5600 2100);
DOT 1 (5600 2150);
DOT 1 (5600 2050);
DOT 1 (5600 2000);
DOT 1 (5600 1950);
DOT 1 (5600 1900);
DOT 1 (5600 1850);
DOT 1 (5600 1800);
DOT 1 (5600 1750);
DOT 1 (5600 1700);
DOT 1 (5600 1650);
DOT 1 (5600 1550);
DOT 1 (5600 1600);
DOT 1 (5600 1500);
DOT 1 (5600 1450);
DOT 1 (5600 1350);
DOT 1 (5600 1300);
DOT 1 (5600 1250);
DOT 1 (5600 1200);
DOT 1 (3900 4150);
DOT 1 (3900 4100);
DOT 1 (3900 4050);
DOT 1 (3900 4000);
DOT 1 (3900 3950);
DOT 1 (3900 3850);
DOT 1 (3900 3800);
DOT 1 (3900 3750);
DOT 1 (3900 3650);
DOT 1 (3900 3600);
DOT 1 (3900 3550);
DOT 1 (3900 3500);
DOT 1 (3900 3450);
DOT 1 (3900 3400);
DOT 1 (3900 3350);
DOT 1 (3900 3300);
DOT 1 (3900 3250);
DOT 1 (3900 3200);
DOT 1 (3900 3100);
DOT 1 (3900 3150);
DOT 1 (3900 3050);
DOT 1 (3900 3000);
DOT 1 (3900 2950);
DOT 1 (3900 2900);
DOT 1 (3900 2850);
DOT 1 (3900 2800);
DOT 1 (3900 2750);
DOT 1 (3900 2700);
DOT 1 (3900 2650);
DOT 1 (3900 2600);
DOT 1 (3900 2550);
DOT 1 (3900 2450);
DOT 1 (3900 2500);
DOT 1 (3900 2400);
DOT 1 (3900 2350);
DOT 1 (3900 2300);
DOT 1 (3900 2250);
DOT 1 (3900 2200);
DOT 1 (3900 2150);
DOT 1 (3900 2000);
DOT 1 (3900 1950);
DOT 1 (3900 1900);
DOT 1 (3900 1800);
DOT 1 (3900 1750);
DOT 1 (3900 1700);
DOT 1 (3900 1650);
DOT 1 (3900 1600);
DOT 1 (3900 1550);
DOT 1 (3900 1500);
DOT 1 (3900 1450);
DOT 1 (3900 1350);
DOT 1 (3900 1300);
DOT 1 (3900 1250);
DOT 1 (3900 1200);
DOT 1 (3900 1150);
DOT 1 (3900 1100);
DOT 1 (2825 225);
DOT 1 (2200 700);
DOT 1 (5600 1400);
DOT 1 (3900 1850);
DOT 1 (3900 2050);
DOT 1 (3900 2100);
DOT 1 (3900 1400);
DOT 1 (3900 3700);
DOT 1 (3900 3900);
DOT 1 (3900 4300);
DOT 1 (3900 4350);
FORCENOTE
20210728 MODIFY FOR GT
(-3450 5025) 0;
DISPLAY LEFT (-3450 5025);
DISPLAY 2.510638 (-3450 5025);
PAINT PINK (-3450 5025);
QUIT
